G04 ================== begin FILE IDENTIFICATION RECORD ==================*
G04 Layout Name:  F:/<user>/2022/FB/R4006-TIMING/brd/gerber-3/R4006-B0001-02_R01.brd*
G04 Film Name:    R4006-B0001-02_R01_BSS*
G04 File Format:  Gerber RS274X*
G04 File Origin:  Cadence Allegro 17.2-S079*
G04 Origin Date:  Fri Feb 25 18:14:43 2022*
G04 *
G04 Layer:  PACKAGE GEOMETRY/SILKSCREEN_BOTTOM*
G04 Layer:  BOARD GEOMETRY/SILKSCREEN_BOTTOM*
G04 Layer:  REF DES/SILKSCREEN_BOTTOM*
G04 Layer:  MANUFACTURING/CELESTICA_LEGEND*
G04 *
G04 Offset:    (0.00 0.00)*
G04 Mirror:    No*
G04 Mode:      Positive*
G04 Rotation:  0*
G04 FullContactRelief:  No*
G04 UndefLineWidth:     6.00*
G04 ================== end FILE IDENTIFICATION RECORD ====================*
%FSLAX55Y55*MOIN*%
%IR0*IPPOS*OFA0.00000B0.00000*MIA0B0*SFA1.00000B1.00000*%
%ADD10C,.01*%
%ADD11C,.005*%
%ADD12C,.006*%
%ADD13C,.007*%
%ADD14C,.008*%
G75*
%LPD*%
G75*
G36*
G01X60880Y307480D02*
G03I-1500J0D01*
G37*
G36*
G01X205500Y358000D02*
G02I-1500J0D01*
G37*
G36*
G01X248470Y213852D02*
G03I-1500J0D01*
G37*
G36*
G01X275100Y213600D02*
G02I-1500J0D01*
G37*
G36*
G01X292000Y225500D02*
G03I-1500J0D01*
G37*
G36*
G01X312500Y223000D02*
G03I-1500J0D01*
G37*
G36*
G01X576300Y257800D02*
G02I-1500J0D01*
G37*
G36*
G01X575800Y286300D02*
G02I-1500J0D01*
G37*
G36*
G01X540376Y376651D02*
Y374651D01*
X522824D01*
Y376651D01*
X540376D01*
G37*
G54D10*
G01X136000Y-65500D02*
Y-158000D01*
X506000D01*
Y-65500D01*
X136000D01*
G01X316000D02*
Y-158000D01*
G54D11*
G01X329433Y-125500D02*
Y-133000D01*
X333167D01*
G01X340480D02*
Y-128000D01*
G01Y-128875D02*
X340107Y-128375D01*
X339547Y-128125D01*
X338893Y-128000D01*
X338240Y-128250D01*
X337680Y-128750D01*
X337307Y-129500D01*
X337120Y-130500D01*
X337307Y-131500D01*
X337680Y-132250D01*
X338240Y-132750D01*
X338893Y-133000D01*
X339547Y-132875D01*
X340107Y-132500D01*
X340480Y-132000D01*
G01X344340Y-135250D02*
X344900Y-135500D01*
X345647Y-135250D01*
X346113Y-134750D01*
X346487Y-134125D01*
X347047Y-132125D01*
X348260Y-128000D01*
G01X345273D02*
X347047Y-132125D01*
G01X352400Y-129625D02*
X355387D01*
X355107Y-128750D01*
X354640Y-128250D01*
X353987Y-128000D01*
X353333Y-128125D01*
X352773Y-128500D01*
X352400Y-129375D01*
X352213Y-130125D01*
Y-130875D01*
X352400Y-131625D01*
X352867Y-132375D01*
X353427Y-132875D01*
X354080Y-133000D01*
X354733Y-132750D01*
X355387Y-132000D01*
G01X359993Y-133000D02*
Y-128000D01*
G01Y-129000D02*
X360460Y-128500D01*
X360927Y-128125D01*
X361580Y-128000D01*
X362047Y-128125D01*
X362607Y-128500D01*
G01X368800Y-133250D02*
X368613Y-133125D01*
Y-132875D01*
X368800Y-132750D01*
X368987Y-132875D01*
Y-133125D01*
X368800Y-133250D01*
G01Y-129875D02*
X368613Y-129750D01*
Y-129500D01*
X368800Y-129375D01*
X368987Y-129500D01*
Y-129750D01*
X368800Y-129875D01*
G01X336747Y-120500D02*
Y-113000D01*
X338613D01*
X339360Y-113375D01*
X339920Y-113875D01*
X340387Y-114625D01*
X340760Y-115500D01*
X340853Y-116750D01*
X340760Y-118000D01*
X340387Y-118875D01*
X339920Y-119625D01*
X339360Y-120125D01*
X338613Y-120500D01*
X336747D01*
G01X347980D02*
Y-115500D01*
G01Y-116375D02*
X347607Y-115875D01*
X347047Y-115625D01*
X346393Y-115500D01*
X345740Y-115750D01*
X345180Y-116250D01*
X344807Y-117000D01*
X344620Y-118000D01*
X344807Y-119000D01*
X345180Y-119750D01*
X345740Y-120250D01*
X346393Y-120500D01*
X347047Y-120375D01*
X347607Y-120000D01*
X347980Y-119500D01*
G01X353800Y-113000D02*
Y-120500D01*
G01X352493Y-115500D02*
X355107D01*
G01X359900Y-117125D02*
X362887D01*
X362607Y-116250D01*
X362140Y-115750D01*
X361487Y-115500D01*
X360833Y-115625D01*
X360273Y-116000D01*
X359900Y-116875D01*
X359713Y-117625D01*
Y-118375D01*
X359900Y-119125D01*
X360367Y-119875D01*
X360927Y-120375D01*
X361580Y-120500D01*
X362233Y-120250D01*
X362887Y-119500D01*
G01X368800Y-120750D02*
X368613Y-120625D01*
Y-120375D01*
X368800Y-120250D01*
X368987Y-120375D01*
Y-120625D01*
X368800Y-120750D01*
G01Y-117375D02*
X368613Y-117250D01*
Y-117000D01*
X368800Y-116875D01*
X368987Y-117000D01*
Y-117250D01*
X368800Y-117375D01*
G01X382027Y-114250D02*
X382587Y-113500D01*
X383240Y-113125D01*
X383987Y-113000D01*
X384920Y-113250D01*
X385573Y-113875D01*
X385760Y-114625D01*
X385667Y-115375D01*
X385293Y-116000D01*
X383427Y-117250D01*
X382587Y-118125D01*
X382027Y-119375D01*
X381840Y-120500D01*
X385760D01*
G01X391300Y-113000D02*
X390553Y-113250D01*
X389993Y-113875D01*
X389620Y-114625D01*
X389340Y-115625D01*
X389247Y-116750D01*
X389340Y-117875D01*
X389620Y-118875D01*
X389993Y-119625D01*
X390553Y-120250D01*
X391300Y-120500D01*
X392047Y-120250D01*
X392607Y-119625D01*
X392980Y-118875D01*
X393260Y-117875D01*
X393353Y-116750D01*
X393260Y-115625D01*
X392980Y-114625D01*
X392607Y-113875D01*
X392047Y-113250D01*
X391300Y-113000D01*
G01X397027Y-114250D02*
X397587Y-113500D01*
X398240Y-113125D01*
X398987Y-113000D01*
X399920Y-113250D01*
X400573Y-113875D01*
X400760Y-114625D01*
X400667Y-115375D01*
X400293Y-116000D01*
X398427Y-117250D01*
X397587Y-118125D01*
X397027Y-119375D01*
X396840Y-120500D01*
X400760D01*
G01X404527Y-114250D02*
X405087Y-113500D01*
X405740Y-113125D01*
X406487Y-113000D01*
X407420Y-113250D01*
X408073Y-113875D01*
X408260Y-114625D01*
X408167Y-115375D01*
X407793Y-116000D01*
X405927Y-117250D01*
X405087Y-118125D01*
X404527Y-119375D01*
X404340Y-120500D01*
X408260D01*
G01X412587Y-118000D02*
X415013D01*
G01X421300Y-113000D02*
X420553Y-113250D01*
X419993Y-113875D01*
X419620Y-114625D01*
X419340Y-115625D01*
X419247Y-116750D01*
X419340Y-117875D01*
X419620Y-118875D01*
X419993Y-119625D01*
X420553Y-120250D01*
X421300Y-120500D01*
X422047Y-120250D01*
X422607Y-119625D01*
X422980Y-118875D01*
X423260Y-117875D01*
X423353Y-116750D01*
X423260Y-115625D01*
X422980Y-114625D01*
X422607Y-113875D01*
X422047Y-113250D01*
X421300Y-113000D01*
G01X427027Y-114250D02*
X427587Y-113500D01*
X428240Y-113125D01*
X428987Y-113000D01*
X429920Y-113250D01*
X430573Y-113875D01*
X430760Y-114625D01*
X430667Y-115375D01*
X430293Y-116000D01*
X428427Y-117250D01*
X427587Y-118125D01*
X427027Y-119375D01*
X426840Y-120500D01*
X430760D01*
G01X435087Y-118000D02*
X437513D01*
G01X442027Y-114250D02*
X442587Y-113500D01*
X443240Y-113125D01*
X443987Y-113000D01*
X444920Y-113250D01*
X445573Y-113875D01*
X445760Y-114625D01*
X445667Y-115375D01*
X445293Y-116000D01*
X443427Y-117250D01*
X442587Y-118125D01*
X442027Y-119375D01*
X441840Y-120500D01*
X445760D01*
G01X449247Y-119375D02*
X449807Y-120000D01*
X450460Y-120375D01*
X451300Y-120500D01*
X452140Y-120250D01*
X452793Y-119750D01*
X453260Y-118875D01*
X453353Y-117875D01*
X453167Y-116875D01*
X452700Y-116250D01*
X452047Y-115750D01*
X451393Y-115625D01*
X450740Y-115750D01*
X449900Y-116250D01*
X450180Y-113000D01*
X452700D01*
G01X336933Y-108000D02*
Y-100500D01*
X339267D01*
X340013Y-100875D01*
X340480Y-101375D01*
X340667Y-102375D01*
X340480Y-103375D01*
X339920Y-104000D01*
X339267Y-104375D01*
X336933D01*
G01X339267D02*
X340667Y-108000D01*
G01X344900Y-104625D02*
X347887D01*
X347607Y-103750D01*
X347140Y-103250D01*
X346487Y-103000D01*
X345833Y-103125D01*
X345273Y-103500D01*
X344900Y-104375D01*
X344713Y-105125D01*
Y-105875D01*
X344900Y-106625D01*
X345367Y-107375D01*
X345927Y-107875D01*
X346580Y-108000D01*
X347233Y-107750D01*
X347887Y-107000D01*
G01X352120Y-103000D02*
X353800Y-108000D01*
X355480Y-103000D01*
G01X368800Y-108250D02*
X368613Y-108125D01*
Y-107875D01*
X368800Y-107750D01*
X368987Y-107875D01*
Y-108125D01*
X368800Y-108250D01*
G01Y-104875D02*
X368613Y-104750D01*
Y-104500D01*
X368800Y-104375D01*
X368987Y-104500D01*
Y-104750D01*
X368800Y-104875D01*
G01X383800Y-100500D02*
X383053Y-100750D01*
X382493Y-101375D01*
X382120Y-102125D01*
X381840Y-103125D01*
X381747Y-104250D01*
X381840Y-105375D01*
X382120Y-106375D01*
X382493Y-107125D01*
X383053Y-107750D01*
X383800Y-108000D01*
X384547Y-107750D01*
X385107Y-107125D01*
X385480Y-106375D01*
X385760Y-105375D01*
X385853Y-104250D01*
X385760Y-103125D01*
X385480Y-102125D01*
X385107Y-101375D01*
X384547Y-100750D01*
X383800Y-100500D01*
G01X391300Y-108000D02*
Y-100500D01*
X390180Y-102000D01*
G01Y-108000D02*
X392420D01*
G01X336933Y-95500D02*
Y-88000D01*
X339173D01*
X339920Y-88375D01*
X340480Y-89250D01*
X340667Y-90250D01*
X340480Y-91250D01*
X340013Y-92000D01*
X339173Y-92375D01*
X336933D01*
G01X344620Y-95750D02*
X347980Y-88000D01*
G01X351653Y-95500D02*
Y-88000D01*
X355947Y-95500D01*
Y-88000D01*
G01X368800Y-95750D02*
X368613Y-95625D01*
Y-95375D01*
X368800Y-95250D01*
X368987Y-95375D01*
Y-95625D01*
X368800Y-95750D01*
G01Y-92375D02*
X368613Y-92250D01*
Y-92000D01*
X368800Y-91875D01*
X368987Y-92000D01*
Y-92250D01*
X368800Y-92375D01*
G01X381933Y-95500D02*
Y-88000D01*
X384267D01*
X385013Y-88375D01*
X385480Y-88875D01*
X385667Y-89875D01*
X385480Y-90875D01*
X384920Y-91500D01*
X384267Y-91875D01*
X381933D01*
G01X384267D02*
X385667Y-95500D01*
G01X392420D02*
Y-88000D01*
X388967Y-93375D01*
X393633D01*
G01X398800Y-88000D02*
X398053Y-88250D01*
X397493Y-88875D01*
X397120Y-89625D01*
X396840Y-90625D01*
X396747Y-91750D01*
X396840Y-92875D01*
X397120Y-93875D01*
X397493Y-94625D01*
X398053Y-95250D01*
X398800Y-95500D01*
X399547Y-95250D01*
X400107Y-94625D01*
X400480Y-93875D01*
X400760Y-92875D01*
X400853Y-91750D01*
X400760Y-90625D01*
X400480Y-89625D01*
X400107Y-88875D01*
X399547Y-88250D01*
X398800Y-88000D01*
G01X406300D02*
X405553Y-88250D01*
X404993Y-88875D01*
X404620Y-89625D01*
X404340Y-90625D01*
X404247Y-91750D01*
X404340Y-92875D01*
X404620Y-93875D01*
X404993Y-94625D01*
X405553Y-95250D01*
X406300Y-95500D01*
X407047Y-95250D01*
X407607Y-94625D01*
X407980Y-93875D01*
X408260Y-92875D01*
X408353Y-91750D01*
X408260Y-90625D01*
X407980Y-89625D01*
X407607Y-88875D01*
X407047Y-88250D01*
X406300Y-88000D01*
G01X412027Y-92375D02*
X412680Y-91500D01*
X413240Y-91000D01*
X413987Y-90750D01*
X414640Y-91000D01*
X415107Y-91500D01*
X415480Y-92250D01*
X415573Y-93125D01*
X415480Y-93875D01*
X415107Y-94625D01*
X414547Y-95250D01*
X413893Y-95500D01*
X413147Y-95250D01*
X412493Y-94500D01*
X412120Y-93375D01*
X412027Y-92125D01*
X412213Y-90500D01*
X412493Y-89625D01*
X412960Y-88750D01*
X413613Y-88125D01*
X414267Y-88000D01*
X414920Y-88250D01*
X415387Y-88875D01*
G01X420087Y-93000D02*
X422513D01*
G01X429547Y-91500D02*
X429920Y-91125D01*
X430200Y-90500D01*
X430387Y-89625D01*
X430200Y-88875D01*
X429827Y-88375D01*
X429173Y-88000D01*
X426653D01*
Y-95500D01*
X429733D01*
X430387Y-95000D01*
X430760Y-94250D01*
X430947Y-93375D01*
X430760Y-92500D01*
X430200Y-91750D01*
X429547Y-91500D01*
X426653D01*
G01X436300Y-88000D02*
X435553Y-88250D01*
X434993Y-88875D01*
X434620Y-89625D01*
X434340Y-90625D01*
X434247Y-91750D01*
X434340Y-92875D01*
X434620Y-93875D01*
X434993Y-94625D01*
X435553Y-95250D01*
X436300Y-95500D01*
X437047Y-95250D01*
X437607Y-94625D01*
X437980Y-93875D01*
X438260Y-92875D01*
X438353Y-91750D01*
X438260Y-90625D01*
X437980Y-89625D01*
X437607Y-88875D01*
X437047Y-88250D01*
X436300Y-88000D01*
G01X443800D02*
X443053Y-88250D01*
X442493Y-88875D01*
X442120Y-89625D01*
X441840Y-90625D01*
X441747Y-91750D01*
X441840Y-92875D01*
X442120Y-93875D01*
X442493Y-94625D01*
X443053Y-95250D01*
X443800Y-95500D01*
X444547Y-95250D01*
X445107Y-94625D01*
X445480Y-93875D01*
X445760Y-92875D01*
X445853Y-91750D01*
X445760Y-90625D01*
X445480Y-89625D01*
X445107Y-88875D01*
X444547Y-88250D01*
X443800Y-88000D01*
G01X451300D02*
X450553Y-88250D01*
X449993Y-88875D01*
X449620Y-89625D01*
X449340Y-90625D01*
X449247Y-91750D01*
X449340Y-92875D01*
X449620Y-93875D01*
X449993Y-94625D01*
X450553Y-95250D01*
X451300Y-95500D01*
X452047Y-95250D01*
X452607Y-94625D01*
X452980Y-93875D01*
X453260Y-92875D01*
X453353Y-91750D01*
X453260Y-90625D01*
X452980Y-89625D01*
X452607Y-88875D01*
X452047Y-88250D01*
X451300Y-88000D01*
G01X458800Y-95500D02*
Y-88000D01*
X457680Y-89500D01*
G01Y-95500D02*
X459920D01*
G01X465087Y-93000D02*
X467513D01*
G01X473800Y-88000D02*
X473053Y-88250D01*
X472493Y-88875D01*
X472120Y-89625D01*
X471840Y-90625D01*
X471747Y-91750D01*
X471840Y-92875D01*
X472120Y-93875D01*
X472493Y-94625D01*
X473053Y-95250D01*
X473800Y-95500D01*
X474547Y-95250D01*
X475107Y-94625D01*
X475480Y-93875D01*
X475760Y-92875D01*
X475853Y-91750D01*
X475760Y-90625D01*
X475480Y-89625D01*
X475107Y-88875D01*
X474547Y-88250D01*
X473800Y-88000D01*
G01X479527Y-89250D02*
X480087Y-88500D01*
X480740Y-88125D01*
X481487Y-88000D01*
X482420Y-88250D01*
X483073Y-88875D01*
X483260Y-89625D01*
X483167Y-90375D01*
X482793Y-91000D01*
X480927Y-92250D01*
X480087Y-93125D01*
X479527Y-94375D01*
X479340Y-95500D01*
X483260D01*
G01X381698Y-131815D02*
X382445Y-132440D01*
X383285Y-132815D01*
X384031D01*
X384778Y-132440D01*
X385338Y-131815D01*
X385618Y-130940D01*
X385431Y-130065D01*
X384965Y-129315D01*
X384125Y-128815D01*
X383005Y-128565D01*
X382351Y-128065D01*
X382071Y-127190D01*
X382258Y-126315D01*
X382725Y-125690D01*
X383378Y-125315D01*
X384031D01*
X384685Y-125565D01*
X385245Y-126190D01*
G01X390038Y-125315D02*
X392278D01*
G01X391158D02*
Y-132815D01*
G01X390038D02*
X392278D01*
G01X396791Y-125315D02*
Y-132815D01*
X400525D01*
G01X404105D02*
Y-125315D01*
G01X407651D02*
X404105Y-129940D01*
G01X408211Y-132815D02*
X405691Y-127815D01*
G01X411698Y-131815D02*
X412445Y-132440D01*
X413285Y-132815D01*
X414031D01*
X414778Y-132440D01*
X415338Y-131815D01*
X415618Y-130940D01*
X415431Y-130065D01*
X414965Y-129315D01*
X414125Y-128815D01*
X413005Y-128565D01*
X412351Y-128065D01*
X412071Y-127190D01*
X412258Y-126315D01*
X412725Y-125690D01*
X413378Y-125315D01*
X414031D01*
X414685Y-125565D01*
X415245Y-126190D01*
G01X423211Y-125940D02*
X422651Y-125565D01*
X421998Y-125315D01*
X421251D01*
X420411Y-125690D01*
X419758Y-126315D01*
X419291Y-127065D01*
X418918Y-128315D01*
X418825Y-129440D01*
X419011Y-130565D01*
X419291Y-131315D01*
X419851Y-132065D01*
X420505Y-132565D01*
X421158Y-132815D01*
X421811D01*
X422465Y-132565D01*
X423025Y-132190D01*
X423491Y-131690D01*
G01X426791Y-132815D02*
Y-125315D01*
X429125D01*
X429871Y-125690D01*
X430338Y-126190D01*
X430525Y-127190D01*
X430338Y-128190D01*
X429778Y-128815D01*
X429125Y-129190D01*
X426791D01*
G01X429125D02*
X430525Y-132815D01*
G01X438025D02*
X434291D01*
Y-125315D01*
X438025D01*
G01X436531Y-128940D02*
X434291D01*
G01X445525Y-132815D02*
X441791D01*
Y-125315D01*
X445525D01*
G01X444031Y-128940D02*
X441791D01*
G01X449011Y-132815D02*
Y-125315D01*
X453305Y-132815D01*
Y-125315D01*
G01X466905Y-128815D02*
X467278Y-128440D01*
X467558Y-127815D01*
X467745Y-126940D01*
X467558Y-126190D01*
X467185Y-125690D01*
X466531Y-125315D01*
X464011D01*
Y-132815D01*
X467091D01*
X467745Y-132315D01*
X468118Y-131565D01*
X468305Y-130690D01*
X468118Y-129815D01*
X467558Y-129065D01*
X466905Y-128815D01*
X464011D01*
G01X473658Y-132815D02*
X472911Y-132690D01*
X472258Y-132190D01*
X471698Y-131440D01*
X471325Y-130565D01*
X471138Y-129565D01*
Y-128565D01*
X471325Y-127565D01*
X471698Y-126690D01*
X472258Y-125940D01*
X472911Y-125440D01*
X473658Y-125315D01*
X474405Y-125440D01*
X475058Y-125940D01*
X475618Y-126690D01*
X475991Y-127565D01*
X476178Y-128565D01*
Y-129565D01*
X475991Y-130565D01*
X475618Y-131440D01*
X475058Y-132190D01*
X474405Y-132690D01*
X473658Y-132815D01*
G01X481158Y-125315D02*
Y-132815D01*
G01X479011Y-125315D02*
X483305D01*
G54D12*
G01X26800Y280500D02*
Y289500D01*
G01X31200Y280500D02*
X26800D01*
G01X26500Y289700D02*
Y285300D01*
G01X17500D02*
Y289700D01*
G01X26500Y285300D02*
X17500D01*
G01Y295300D02*
Y299700D01*
G01X26500Y295300D02*
X17500D01*
G01X26500Y299700D02*
Y295300D01*
G01X17500Y299700D02*
X26500D01*
G01Y304700D02*
Y300300D01*
G01X17500D02*
Y304700D01*
G01X26500Y300300D02*
X17500D01*
G01X26800Y289500D02*
X31200D01*
G01X17500Y290300D02*
Y294700D01*
G01X26500Y290300D02*
X17500D01*
G01X26500Y294700D02*
Y290300D01*
G01X17500Y294700D02*
X26500D01*
G01X17500Y289700D02*
X26500D01*
G01X17500Y305300D02*
Y309700D01*
G01X26500Y305300D02*
X17500D01*
G01X26500Y309700D02*
Y305300D01*
G01X17500Y309700D02*
X26500D01*
G01X17500Y304700D02*
X26500D01*
G01X35700Y280500D02*
X31300D01*
G01D02*
Y289500D01*
G01X35700D02*
Y280500D01*
G01X31200Y289500D02*
Y280500D01*
G01X31300Y289500D02*
X35700D01*
G01X32950Y293260D02*
Y304740D01*
G01X39000Y293260D02*
X32950D01*
G01X39000Y292000D02*
Y293260D01*
G01X53000Y292000D02*
X39000D01*
G01X32950Y304740D02*
X39000D01*
G01Y306000D02*
X53000D01*
G01X39000Y304740D02*
Y306000D01*
G01X61100Y59300D02*
Y63700D01*
G01X70100Y59300D02*
X61100D01*
G01Y63700D02*
X70100D01*
G01X55500Y72100D02*
X59900D01*
G01X55500Y63100D02*
Y72100D01*
G01X59900Y63100D02*
X55500D01*
G01X59900Y72100D02*
Y63100D01*
G01X55200D02*
X50800D01*
G01X55200Y72100D02*
Y63100D01*
G01X50800Y72100D02*
X55200D01*
G01X50800Y63100D02*
Y72100D01*
G01X51300Y86000D02*
Y95000D01*
G01X55700Y86000D02*
X51300D01*
G01X55700Y95000D02*
Y86000D01*
G01X51300Y95000D02*
X55700D01*
G01X50800Y142000D02*
Y151000D01*
G01X55200Y142000D02*
X50800D01*
G01X55200Y151000D02*
Y142000D01*
G01X50800Y151000D02*
X55200D01*
G01X50800Y211500D02*
X55200D01*
G01X50800Y202500D02*
Y211500D01*
G01X55200Y202500D02*
X50800D01*
G01X55200Y211500D02*
Y202500D01*
G01X50800Y265000D02*
X55200D01*
G01X50800Y256000D02*
Y265000D01*
G01X55200Y256000D02*
X50800D01*
G01X55200Y265000D02*
Y256000D01*
G01X53000Y293260D02*
Y292000D01*
G01X59050Y293260D02*
X53000D01*
G01X59050Y304740D02*
Y293260D01*
G01X53000Y304740D02*
X59050D01*
G01X53000Y306000D02*
Y304740D01*
G01X70100Y63700D02*
Y59300D01*
G01X78500Y68700D02*
X87500D01*
G01X78500Y64300D02*
Y68700D01*
G01X87500Y64300D02*
X78500D01*
G01X77700Y68700D02*
Y77700D01*
G01X82100Y68700D02*
X77700D01*
G01X69900Y88300D02*
X74300D01*
G01X69900Y79300D02*
Y88300D01*
G01X74300Y79300D02*
X69900D01*
G01X74300Y88300D02*
Y79300D01*
G01X76500Y88700D02*
X72100D01*
G01X76500Y97700D02*
Y88700D01*
G01X72100D02*
Y97700D01*
G01X81000Y88700D02*
X76600D01*
G01D02*
Y97700D01*
G01X77700Y77700D02*
X82100D01*
G01X67600Y88700D02*
Y97700D01*
G01X72000Y88700D02*
X67600D01*
G01X72000Y97700D02*
Y88700D01*
G01X72100Y97700D02*
X76500D01*
G01X76600D02*
X81000D01*
G01X67600D02*
X72000D01*
G01X65100Y152200D02*
Y156600D01*
G01X74100Y152200D02*
X65100D01*
G01Y156600D02*
X74100D01*
G01D02*
Y152200D01*
G01X78400Y161700D02*
Y166100D01*
G01X87400Y161700D02*
X78400D01*
G01Y161600D02*
X87400D01*
G01X78400Y157200D02*
Y161600D01*
G01X87400Y157200D02*
X78400D01*
G01X78000Y152200D02*
X87000D01*
G01X78000Y147800D02*
Y152200D01*
G01X87000Y147800D02*
X78000D01*
G01X65000Y147300D02*
Y151700D01*
G01X74000Y147300D02*
X65000D01*
G01Y151700D02*
X74000D01*
G01D02*
Y147300D01*
G01X78400Y157100D02*
X87400D01*
G01X78400Y152700D02*
Y157100D01*
G01X87400Y152700D02*
X78400D01*
G01X65200Y157700D02*
Y162100D01*
G01X74200Y157700D02*
X65200D01*
G01Y162100D02*
X74200D01*
G01D02*
Y157700D01*
G01X78400Y170600D02*
X87400D01*
G01X78400Y166200D02*
Y170600D01*
G01X87400Y166200D02*
X78400D01*
G01Y166100D02*
X87400D01*
G01X73800Y246800D02*
X78200D01*
G01X73800Y237800D02*
Y246800D01*
G01X78200Y237800D02*
X73800D01*
G01X78200Y246800D02*
Y237800D01*
G01X78300Y246800D02*
X82700D01*
G01X78300Y237800D02*
Y246800D01*
G01X82700Y237800D02*
X78300D01*
G01X73700D02*
X69300D01*
G01X73700Y246800D02*
Y237800D01*
G01X69300Y246800D02*
X73700D01*
G01X69300Y237800D02*
Y246800D01*
G01X63800Y299000D02*
Y308000D01*
G01X68200Y299000D02*
X63800D01*
G01X68200Y308000D02*
Y299000D01*
G01X76500Y293700D02*
Y289300D01*
G01X67500Y293700D02*
X76500D01*
G01X67500Y289300D02*
Y293700D01*
G01X76500Y289300D02*
X67500D01*
G01X63800Y308000D02*
X68200D01*
G01X77000Y322200D02*
Y317800D01*
G01D02*
X68000D01*
G01D02*
Y322200D01*
G01X77000Y317700D02*
Y313300D01*
G01X68000Y317700D02*
X77000D01*
G01X68000Y313300D02*
Y317700D01*
G01X77000Y313300D02*
X68000D01*
G01X67800Y336000D02*
Y345000D01*
G01X72200Y336000D02*
X67800D01*
G01X72200Y345000D02*
Y336000D01*
G01X68000Y326700D02*
X77000D01*
G01D02*
Y322300D01*
G01D02*
X68000D01*
G01D02*
Y326700D01*
G01Y322200D02*
X77000D01*
G01X67800Y345000D02*
X72200D01*
G01X82300Y68800D02*
Y73200D01*
G01X91300Y68800D02*
X82300D01*
G01Y73200D02*
X91300D01*
G01D02*
Y68800D01*
G01X87500Y68700D02*
Y64300D01*
G01X82100Y77700D02*
Y68700D01*
G01X88200Y76700D02*
X83800D01*
G01Y85700D02*
X88200D01*
G01X83800Y76700D02*
Y85700D01*
G01X88200D02*
Y76700D01*
G01X81000Y97700D02*
Y88700D01*
G01X85600D02*
Y97700D01*
G01X90000Y88700D02*
X85600D01*
G01X90000Y97700D02*
Y88700D01*
G01X81100D02*
Y97700D01*
G01X85500Y88700D02*
X81100D01*
G01X85500Y97700D02*
Y88700D01*
G01X85600Y97700D02*
X90000D01*
G01X81100D02*
X85500D01*
G01X87400Y166100D02*
Y161700D01*
G01Y161600D02*
Y157200D01*
G01X87000Y152200D02*
Y147800D01*
G01X87400Y157100D02*
Y152700D01*
G01Y170600D02*
Y166200D01*
G01X82700Y246800D02*
Y237800D01*
G01X91800D02*
X87400D01*
G01X91800Y246800D02*
Y237800D01*
G01X87400Y246800D02*
X91800D01*
G01X87400Y237800D02*
Y246800D01*
G01X87200Y237800D02*
X82800D01*
G01Y246800D02*
X87200D01*
G01X82800Y237800D02*
Y246800D01*
G01X87200D02*
Y237800D01*
G01X88600Y276500D02*
Y285500D01*
G01X93000Y276500D02*
X88600D01*
G01X93000Y285500D02*
Y276500D01*
G01X88000D02*
X83600D01*
G01D02*
Y285500D01*
G01X88000D02*
Y276500D01*
G01X88600Y285500D02*
X93000D01*
G01X83600D02*
X88000D01*
G01X84500Y343300D02*
Y347700D01*
G01X93500Y343300D02*
X84500D01*
G01Y347700D02*
X93500D01*
G01D02*
Y343300D01*
G01X97200Y354000D02*
X92800D01*
G01D02*
Y363000D01*
G01X90400Y352900D02*
X86000D01*
G01X90400Y361900D02*
Y352900D01*
G01X86000D02*
Y361900D01*
G01X84500Y347800D02*
Y352200D01*
G01X93500Y347800D02*
X84500D01*
G01Y352200D02*
X93500D01*
G01D02*
Y347800D01*
G01X84500Y338800D02*
Y343200D01*
G01X93500Y338800D02*
X84500D01*
G01Y343200D02*
X93500D01*
G01D02*
Y338800D01*
G01X92800Y363000D02*
X97200D01*
G01X86000Y361900D02*
X90400D01*
G01X101400Y74000D02*
X110400D01*
G01X101400Y69600D02*
Y74000D01*
G01X110400Y69600D02*
X101400D01*
G01X110400Y74000D02*
Y69600D01*
G01X101300Y316000D02*
X105700D01*
G01X101300Y307000D02*
Y316000D01*
G01X105700Y307000D02*
X101300D01*
G01X105700Y316000D02*
Y307000D01*
G01X115200Y354000D02*
X110800D01*
G01D02*
Y363000D01*
G01X113000Y345300D02*
Y349700D01*
G01X122000Y345300D02*
X113000D01*
G01Y349700D02*
X122000D01*
G01X97300Y354000D02*
Y363000D01*
G01X101700Y354000D02*
X97300D01*
G01X101700Y363000D02*
Y354000D01*
G01X101800D02*
Y363000D01*
G01X106200Y354000D02*
X101800D01*
G01X106200Y363000D02*
Y354000D01*
G01X97200Y363000D02*
Y354000D01*
G01X110700D02*
X106300D01*
G01X110700Y363000D02*
Y354000D01*
G01X106300D02*
Y363000D01*
G01X106200Y343300D02*
X111800D01*
G01X106200Y353700D02*
Y343300D01*
G01X111800Y353700D02*
X106200D01*
G01X111800Y343300D02*
Y353700D01*
G01X110800Y363000D02*
X115200D01*
G01X103300Y366500D02*
Y375500D01*
G01X107700Y366500D02*
X103300D01*
G01X107700Y375500D02*
Y366500D01*
G01X97300Y363000D02*
X101700D01*
G01X101800D02*
X106200D01*
G01X106300D02*
X110700D01*
G01X103300Y375500D02*
X107700D01*
G01X128500Y73100D02*
Y77500D01*
G01X137500Y73100D02*
X128500D01*
G01X114970Y73060D02*
X123970D01*
G01X114970Y68660D02*
Y73060D01*
G01X123970Y68660D02*
X114970D01*
G01X123970Y73060D02*
Y68660D01*
G01X114980Y63670D02*
Y68070D01*
G01X123980Y63670D02*
X114980D01*
G01Y68070D02*
X123980D01*
G01D02*
Y63670D01*
G01X128450Y68000D02*
X137450D01*
G01X128450Y63600D02*
Y68000D01*
G01X137450Y63600D02*
X128450D01*
G01X128470Y73000D02*
X137470D01*
G01X128470Y68600D02*
Y73000D01*
G01X137470Y68600D02*
X128470D01*
G01X128500Y77500D02*
X137500D01*
G01X125800Y316000D02*
X130200D01*
G01X125800Y307000D02*
Y316000D01*
G01X130200Y307000D02*
X125800D01*
G01X130200Y316000D02*
Y307000D01*
G01X131500Y325800D02*
Y330200D01*
G01X140500Y325800D02*
X131500D01*
G01Y330200D02*
X140500D01*
G01X131500Y321300D02*
Y325700D01*
G01X140500Y321300D02*
X131500D01*
G01Y325700D02*
X140500D01*
G01X131000Y347800D02*
Y352200D01*
G01X140000Y347800D02*
X131000D01*
G01Y352200D02*
X140000D01*
G01X115200Y363000D02*
Y354000D01*
G01X122000Y349700D02*
Y345300D01*
G01X128700Y354000D02*
X124300D01*
G01X128700Y363000D02*
Y354000D01*
G01X124300D02*
Y363000D01*
G01X119700Y354000D02*
X115300D01*
G01X119700Y363000D02*
Y354000D01*
G01X115300D02*
Y363000D01*
G01X124200Y354000D02*
X119800D01*
G01D02*
Y363000D01*
G01X124200D02*
Y354000D01*
G01X129200Y352300D02*
X134800D01*
G01X129200Y362700D02*
Y352300D01*
G01X124300Y363000D02*
X128700D01*
G01X115300D02*
X119700D01*
G01X119800D02*
X124200D01*
G01X134800Y362700D02*
X129200D01*
G01X145964Y-110118D02*
G03I-634J0D01*
G01X149695D02*
G03I-1038J0D01*
G01X137500Y77500D02*
Y73100D01*
G01X137450Y68000D02*
Y63600D01*
G01X137470Y73000D02*
Y68600D01*
G01X145500Y302200D02*
X154500D01*
G01X145500Y297800D02*
Y302200D01*
G01X154500Y297800D02*
X145500D01*
G01X140500Y330200D02*
Y325800D01*
G01Y325700D02*
Y321300D01*
G01X140000Y352200D02*
Y347800D01*
G01X135300Y353500D02*
Y362500D01*
G01X139700Y353500D02*
X135300D01*
G01X139700Y362500D02*
Y353500D01*
G01X134800Y352300D02*
Y362700D01*
G01X135300Y362500D02*
X139700D01*
G01X141100Y387900D02*
Y392300D01*
G01X150100Y387900D02*
X141100D01*
G01X140100Y382900D02*
Y387300D01*
G01X149100Y382900D02*
X140100D01*
G01X149100Y387300D02*
Y382900D01*
G01X140100Y387300D02*
X149100D01*
G01X141100Y401400D02*
Y405800D01*
G01X150100Y401400D02*
X141100D01*
G01Y405800D02*
X150100D01*
G01X141100Y392300D02*
X150100D01*
G01X141100Y396800D02*
X150100D01*
G01X141100Y392400D02*
Y396800D01*
G01X150100Y392400D02*
X141100D01*
G01Y401300D02*
X150100D01*
G01X141100Y396900D02*
Y401300D01*
G01X150100Y396900D02*
X141100D01*
G01X139300Y411800D02*
Y406200D01*
G01D02*
X149700D01*
G01Y411800D02*
X139300D01*
G01X141100Y416400D02*
X150100D01*
G01X141100Y412000D02*
Y416400D01*
G01X150100Y412000D02*
X141100D01*
G01X168013Y-137456D02*
G03I-634J0D01*
G01X155900Y-133655D02*
G03I-632J0D01*
G01X161735Y-128639D02*
G03I-1458J0D01*
G01X158530Y-131428D02*
G03I-1041J0D01*
G01X158461Y-119126D02*
G03I-1283J0D01*
G01X162690Y-117490D02*
G03I-1584J0D01*
G01X169809Y-121292D02*
G03I-2180J0D01*
G01X165531Y-125255D02*
G03I-1869J0D01*
G01X167813Y-115513D02*
G03I-1971J0D01*
G01X154775Y-120500D02*
G03I-892J0D01*
G01X162681Y-102774D02*
G03I-1584J0D01*
G01X158451Y-101149D02*
G03I-1283J0D01*
G01X159258Y-110118D02*
G03I-1868J0D01*
G01X169812Y-98951D02*
G03I-2180J0D01*
G01X167802Y-104739D02*
G03I-1971J0D01*
G01X165183Y-110118D02*
G03I-2180J0D01*
G01X171881D02*
G03I-2642J0D01*
G01X152135Y-98681D02*
G03I-632J0D01*
G01X154064Y-110118D02*
G03I-1460J0D01*
G01X154764Y-99775D02*
G03I-892J0D01*
G01X158530Y-88809D02*
G03I-1041J0D01*
G01X161742Y-91601D02*
G03I-1458J0D01*
G01X165531Y-94981D02*
G03I-1869J0D01*
G01X154500Y302200D02*
Y297800D01*
G01X160800Y348000D02*
Y357000D01*
G01X165200Y348000D02*
X160800D01*
G01X165200Y357000D02*
Y348000D01*
G01X160800Y357000D02*
X165200D01*
G01X150100Y392300D02*
Y387900D01*
G01X151600Y379800D02*
X160600D01*
G01X151600Y375400D02*
Y379800D01*
G01X160600Y375400D02*
X151600D01*
G01X160600Y379800D02*
Y375400D01*
G01X160000Y386300D02*
Y390700D01*
G01X169000Y386300D02*
X160000D01*
G01X150100Y405800D02*
Y401400D01*
G01Y396800D02*
Y392400D01*
G01Y401300D02*
Y396900D01*
G01X160000Y390700D02*
X169000D01*
G01X149700Y406200D02*
Y411800D01*
G01X150100Y416400D02*
Y412000D01*
G01X171080Y-131739D02*
G03I-1282J0D01*
G01X169322Y-135033D02*
G03I-892J0D01*
G01X180669Y-131528D02*
G03I-1870J0D01*
G01X180255Y-136311D02*
G03I-1456J0D01*
G01X179841Y-140261D02*
G03I-1042J0D01*
G01X179433Y-143587D02*
G03I-634J0D01*
G01X181439Y-119680D02*
G03I-2640J0D01*
G01X175373Y-123081D02*
G03I-1968J0D01*
G01X173018Y-127816D02*
G03I-1584J0D01*
G01X174681Y-116876D02*
G03I-2640J0D01*
G01X180979Y-125917D02*
G03I-2180J0D01*
G01X186177Y-123075D02*
G03I-1971J0D01*
G01X188199Y-116876D02*
G03I-2640J0D01*
G01X175452Y-97124D02*
G03I-1968J0D01*
G01X186225Y-97178D02*
G03I-1971J0D01*
G01X181439Y-100556D02*
G03I-2640J0D01*
G01X174681Y-103361D02*
G03I-2640J0D01*
G01X188199D02*
G03I-2640J0D01*
G01X179841Y-79975D02*
G03I-1042J0D01*
G01X171217Y-88444D02*
G03I-1282J0D01*
G01X173123Y-92378D02*
G03I-1584J0D01*
G01X180255Y-83924D02*
G03I-1456J0D01*
G01X180669Y-88708D02*
G03I-1870J0D01*
G01X180979Y-94320D02*
G03I-2180J0D01*
G01X179433Y-76648D02*
G03I-634J0D01*
G01X170600Y336800D02*
X177200D01*
G01X170600Y355800D02*
Y336800D01*
G01X177200Y335650D02*
X194600D01*
G01X177200Y336800D02*
Y335650D01*
G01Y355800D02*
X170600D01*
G01X194600Y356950D02*
X177200D01*
G01D02*
Y355800D01*
G01X170000Y388800D02*
Y393200D01*
G01X179000Y388800D02*
X170000D01*
G01X179000Y393200D02*
Y388800D01*
G01X169000Y390700D02*
Y386300D01*
G01X170000Y393200D02*
X179000D01*
G01X182200Y400000D02*
X177800D01*
G01X182200Y409000D02*
Y400000D01*
G01X177800D02*
Y409000D01*
G01D02*
X182200D01*
G01X177800Y409300D02*
Y416700D01*
G01X190200Y409300D02*
X177800D01*
G01Y416700D02*
X190200D01*
G01X191096Y-134658D02*
G03I-892J0D01*
G01X192135Y-136781D02*
G03I-631J0D01*
G01X198775Y-128635D02*
G03I-1458J0D01*
G01X195808Y-125255D02*
G03I-1869J0D01*
G01X200547Y-113952D02*
G03X203345Y-117196I7247J3422D01*
G01X192148Y-121285D02*
G03I-2180J0D01*
G01X187928Y-127802D02*
G03I-1584J0D01*
G01X189667Y-131511D02*
G03I-1283J0D01*
G01X200699Y-105836D02*
G03X200547Y-113953I8974J-4228D01*
G01X208284Y-101612D02*
G03X200698Y-105835I-219J-8531D01*
G01X192148Y-98951D02*
G03I-2180J0D01*
G01X191108Y-82727D02*
G03I-634J0D01*
G01X190184Y-85250D02*
G03I-893J0D01*
G01X195808Y-94981D02*
G03I-1869J0D01*
G01X187839Y-92457D02*
G03I-1584J0D01*
G01X189190Y-88538D02*
G03I-1283J0D01*
G01X184260Y57820D02*
Y66820D01*
G01X188660D02*
Y57820D01*
G01D02*
X184260D01*
G01Y66820D02*
X188660D01*
G01X190700Y291500D02*
X186300D01*
G01Y300500D02*
X190700D01*
G01X186300Y291500D02*
Y300500D01*
G01X190700D02*
Y291500D01*
G01X201200Y336800D02*
Y355800D01*
G01X194600Y336800D02*
X201200D01*
G01X194600Y335650D02*
Y336800D01*
G01Y355800D02*
Y356950D01*
G01X201200Y355800D02*
X194600D01*
G01X190200Y416700D02*
Y409300D01*
G01X214259Y-115661D02*
G03X213314Y-114453I-714J415D01*
G01X202049Y-108260D02*
G03X205722Y-116181I7039J-1548D01*
G01X218075Y-112869D02*
G03X219083Y-115752I4343J-99D01*
G01X208854Y-116658D02*
G03X213313Y-114452I-2485J10632D01*
G01X208470Y-118462D02*
G03X214261Y-115663I-1122J9711D01*
G01X203346Y-117195D02*
G03X208470Y-118461I4545J7394D01*
G01X205721Y-116179D02*
G03X208853Y-116659I2561J6250D01*
G01X215903Y-114020D02*
G03X219079Y-118061I6190J1597D01*
G01X215904Y-114020D02*
Y-111835D01*
G01X227413Y-112869D02*
X218074D01*
G01X214175Y-103951D02*
G03X208283Y-101613I-6403J-7542D01*
G01X213150Y-105147D02*
G03X214175Y-103951I410J686D01*
G01X213152Y-105146D02*
G03X208030Y-103430I-5122J-6786D01*
G01X208029Y-103429D02*
G03X202049Y-108259I-48J-6058D01*
G01X225189Y-111399D02*
G03X218071I-3559J159D01*
G01X218070Y-111418D02*
Y-111399D01*
G01X225188Y-111418D02*
X218070D01*
G01X227412Y-111835D02*
G03X215906I-5753J223D01*
G01X213300Y59000D02*
Y68000D01*
G01D02*
X217700D01*
G01D02*
Y59000D01*
G01D02*
X213300D01*
G01X217800D02*
Y68000D01*
G01D02*
X222200D01*
G01Y59000D02*
X217800D01*
G01X215100Y299700D02*
X219500D01*
G01X215100Y290700D02*
Y299700D01*
G01X219500Y290700D02*
X215100D01*
G01X210600Y299700D02*
X215000D01*
G01X210600Y290700D02*
Y299700D01*
G01X215000Y290700D02*
X210600D01*
G01X215000Y299700D02*
Y290700D01*
G01X206100Y299700D02*
X210500D01*
G01X206100Y290700D02*
Y299700D01*
G01X210500Y290700D02*
X206100D01*
G01X210500Y299700D02*
Y290700D01*
G01X217000Y338200D02*
Y333800D01*
G01X208000D02*
Y338200D01*
G01X217000Y333800D02*
X208000D01*
G01X208300Y347500D02*
X212700D01*
G01X208300Y338500D02*
Y347500D01*
G01X212700Y338500D02*
X208300D01*
G01X212700Y347500D02*
Y338500D01*
G01X208000Y338200D02*
X217000D01*
G01Y357200D02*
Y352800D01*
G01X208000D02*
Y357200D01*
G01X217000Y352800D02*
X208000D01*
G01X217000Y352200D02*
Y347800D01*
G01X208000Y352200D02*
X217000D01*
G01X208000Y347800D02*
Y352200D01*
G01X217000Y347800D02*
X208000D01*
G01Y357200D02*
X217000D01*
G01X230059Y-117625D02*
Y-102034D01*
G01X230060Y-117626D02*
G03X232080I1010J239D01*
G01X226590Y-116472D02*
G03X225311Y-115210I-817J451D01*
G01X234673Y-114020D02*
G03X237849Y-118061I6190J1597D01*
G01X232081Y-102041D02*
Y-117625D01*
G01X219083Y-115753D02*
G03X225311Y-115211I2844J3371D01*
G01X219079Y-118060D02*
G03X226591Y-116473I2662J5972D01*
G01X227413Y-111835D02*
Y-112869D01*
G01X232080Y-102041D02*
G03X230060Y-102034I-1011J-236D01*
G01X225188Y-111399D02*
Y-111418D01*
G01X234675Y-114020D02*
Y-111835D01*
G01X246181D02*
G03X234675I-5753J223D01*
G01X232110Y55990D02*
Y64990D01*
G01X236510Y55990D02*
X232110D01*
G01X222200Y68000D02*
Y59000D01*
G01X232110Y64990D02*
X236510D01*
G01X228800Y59800D02*
Y70200D01*
G01D02*
X223200D01*
G01D02*
Y59800D01*
G01D02*
X228800D01*
G01X219500Y299700D02*
Y290700D01*
G01X252849Y-116771D02*
G03X254892Y-115895I-74J2994D01*
G01X236844Y-112869D02*
G03X237852Y-115752I4343J-99D01*
G01X237848Y-118060D02*
G03X245360Y-116473I2662J5972D01*
G01X245358Y-116472D02*
G03X244079Y-115210I-817J451D01*
G01X237852Y-115753D02*
G03X244080Y-115211I2844J3371D01*
G01X249566Y-115529D02*
G03X252307Y-116760I2985J2980D01*
G01Y-116761D02*
G03X252849Y-116772I366J4691D01*
G01X250282Y-118087D02*
G03X254318Y-118340I2605J9244D01*
G01X247897Y-116444D02*
G03X250283Y-118086I3752J2898D01*
G01X249568Y-115529D02*
G03X247898Y-116443I-748J-616D01*
G01X255608Y-108618D02*
G03X253612Y-107689I-3116J-4086D01*
G01X246181Y-111835D02*
Y-112869D01*
G01D02*
X236844D01*
G01X255002Y-114328D02*
G03X252723Y-112986I-3540J-3405D01*
G01X249955Y-112030D02*
G03X252723Y-112985I8208J19302D01*
G01X243957Y-111399D02*
Y-111418D01*
G01X243958Y-111399D02*
G03X236840I-3559J159D01*
G01X236841Y-111418D02*
Y-111399D01*
G01X243957Y-111418D02*
X236841D01*
G01X248537Y-109748D02*
G03X249956Y-112031I2652J66D01*
G01X248537Y-108250D02*
Y-109748D01*
G01X250179Y-106359D02*
G03X248537Y-108249I2747J-4045D01*
G01X256884Y-107368D02*
G03X250178Y-106359I-4153J-4811D01*
G01X253611Y-107689D02*
G03X251080Y-107949I-869J-3992D01*
G01X251081Y-107948D02*
G03X250837Y-110104I805J-1183D01*
G01Y-110106D02*
G03X254306Y-111513I5270J8013D01*
G01X237111Y56000D02*
Y65000D01*
G01X241511D02*
Y56000D01*
G01D02*
X237111D01*
G01X236510Y64990D02*
Y55990D01*
G01X243922Y56000D02*
Y65000D01*
G01X248322D02*
Y56000D01*
G01D02*
X243922D01*
G01X248922D02*
Y65000D01*
G01X253322D02*
Y56000D01*
G01D02*
X248922D01*
G01X237111Y65000D02*
X241511D01*
G01X243922D02*
X248322D01*
G01X248922D02*
X253322D01*
G01X251800Y215000D02*
Y224000D01*
G01X256200Y215000D02*
X251800D01*
G01X239791Y227751D02*
Y231600D01*
G01X238770Y227751D02*
X239791D01*
G01X238770Y220249D02*
Y227751D01*
G01X239791Y220249D02*
X238770D01*
G01X239791Y216400D02*
Y220249D01*
G01X248209Y216400D02*
X239791D01*
G01Y231600D02*
X248209D01*
G01Y220249D02*
Y216400D01*
G01X249230Y220249D02*
X248209D01*
G01X249230Y227751D02*
Y220249D01*
G01X248209Y227751D02*
X249230D01*
G01X248209Y231600D02*
Y227751D01*
G01X256200Y224000D02*
X251800D01*
G01D02*
Y233000D01*
G01D02*
X256200D01*
G01X251800Y224000D02*
X256200D01*
G01X239500Y237700D02*
X248500D01*
G01X239500Y233300D02*
Y237700D01*
G01X248500Y233300D02*
X239500D01*
G01X248500Y237700D02*
Y233300D01*
G01Y235300D02*
Y239700D01*
G01X257500Y235300D02*
X248500D01*
G01Y239700D02*
X257500D01*
G01X260954Y-116041D02*
Y-107954D01*
G01X254892Y-115895D02*
G03X255001Y-114328I-764J840D01*
G01X269619Y-117484D02*
Y-106797D01*
G01X269620Y-117484D02*
G03X271926I1153J198D01*
G01X266864Y-117375D02*
G03X266002Y-116329I-764J249D01*
G01X262978Y-115462D02*
G03X266002Y-116329I2046J1428D01*
G01X260955Y-116043D02*
G03X264164Y-118351I2956J725D01*
G01X265463Y-118350D02*
X264165D01*
G01X265464Y-118352D02*
G03X266864Y-117374I-24J1525D01*
G01X256906Y-116470D02*
G03X257054Y-113728I-3143J1545D01*
G01X254317Y-118340D02*
G03X256906Y-116470I-1259J4470D01*
G01X262978Y-107954D02*
Y-115463D01*
G01X257054Y-113729D02*
G03X254307Y-111513I-3470J-1490D01*
G01X271969Y-102342D02*
G03I-1194J0D01*
G01X271926Y-106797D02*
G03X269620I-1153J-409D01*
G01X266003Y-107954D02*
X262978D01*
G01X266004Y-107955D02*
G03X266008Y-105932I-177J1012D01*
G01X262978D02*
X266008D01*
G01X262971Y-103419D02*
X262978Y-105932D01*
G01X262972Y-103418D02*
G03X260954Y-103491I-1005J-141D01*
G01Y-105932D02*
Y-103492D01*
G01X259930Y-105932D02*
X260954D01*
G01X259930D02*
G03X259981Y-107955I298J-1005D01*
G01X260954Y-107954D02*
X259982D01*
G01X255606Y-108620D02*
G03X256885Y-107367I599J667D01*
G01X263607Y56000D02*
Y65000D01*
G01X268007D02*
Y56000D01*
G01D02*
X263607D01*
G01X268607D02*
Y65000D01*
G01X273007Y56000D02*
X268607D01*
G01X263607Y65000D02*
X268007D01*
G01X268607D02*
X273007D01*
G01X256200Y224000D02*
Y215000D01*
G01X256800Y224000D02*
Y233000D01*
G01X261200Y224000D02*
X256800D01*
G01Y233000D02*
X261200D01*
G01D02*
Y224000D01*
G01X256200Y233000D02*
Y224000D01*
G01X263260Y216000D02*
X274740D01*
G01X263260Y220850D02*
Y216000D01*
G01X262291Y220850D02*
X263260D01*
G01X262291Y229150D02*
Y220850D01*
G01X263260Y229150D02*
X262291D01*
G01X263260Y234000D02*
Y229150D01*
G01X267260D02*
Y234000D01*
G01X270740Y229150D02*
X267260D01*
G01X270740Y234000D02*
Y229150D01*
G01X257500Y239700D02*
Y235300D01*
G01Y239700D02*
X266500D01*
G01X257500Y235300D02*
Y239700D01*
G01X266500Y235300D02*
X257500D01*
G01X266500Y239700D02*
Y235300D01*
G01X267260Y234000D02*
X263260D01*
G01X274740D02*
X270740D01*
G01X290671Y-110842D02*
G03X290703Y-118351I860J-3751D01*
G01X276837Y-114305D02*
G03X278891Y-116297I4069J2141D01*
G01X274529Y-113568D02*
G03X275888Y-116443I5718J944D01*
G01X275887D02*
G03X279572Y-118352I4392J3967D01*
G01X281425Y-118350D02*
X279571D01*
G01X281425D02*
G03X284525Y-117161I0J4636D01*
G01X285201Y-116508D02*
X284524Y-117161D01*
G01X285201Y-116508D02*
G03X283966Y-115211I-695J574D01*
G01X281510Y-116675D02*
G03X283966Y-115212I-989J4453D01*
G01X278889Y-116297D02*
G03X281508Y-116677I1946J4197D01*
G01X271926Y-106797D02*
Y-117484D01*
G01X274529Y-113566D02*
Y-111839D01*
G01X276446Y-112943D02*
G03X276837Y-114305I4162J458D01*
G01X276445Y-112066D02*
Y-112943D01*
G01X283833Y-109274D02*
G03X285403Y-108106I585J852D01*
G01X285402D02*
G03X280919Y-105777I-4776J-3714D01*
G01X279541D02*
X280919D01*
G01X279540D02*
G03X274999Y-109274I1260J-6333D01*
G01X274998D02*
G03X274529Y-111839I9988J-3152D01*
G01X276849Y-109932D02*
G03X276446Y-112066I5467J-2137D01*
G01X280036Y-107542D02*
G03X276849Y-109933I664J-4205D01*
G01X282662Y-108199D02*
G03X280037Y-107539I-2313J-3650D01*
G01X283833Y-109275D02*
G03X282662Y-108202I-9277J-8949D01*
G01X273007Y65000D02*
Y56000D01*
G01X277855D02*
Y65000D01*
G01X282255D02*
Y56000D01*
G01D02*
X277855D01*
G01X282855D02*
Y65000D01*
G01X287255D02*
Y56000D01*
G01D02*
X282855D01*
G01X277855Y65000D02*
X282255D01*
G01X282855D02*
X287255D01*
G01X277250Y192300D02*
Y196700D01*
G01X286250Y192300D02*
X277250D01*
G01Y196700D02*
X286250D01*
G01D02*
Y192300D01*
G01X281700Y190400D02*
Y181400D01*
G01X277300D02*
Y190400D01*
G01D02*
X281700D01*
G01Y181400D02*
X277300D01*
G01X281200Y214000D02*
X276800D01*
G01D02*
Y223000D01*
G01X281200D02*
Y214000D01*
G01X287300Y214300D02*
Y224700D01*
G01X281700Y214300D02*
X287300D01*
G01X281700Y224700D02*
Y214300D01*
G01X276800Y227200D02*
Y236200D01*
G01X281200Y227200D02*
X276800D01*
G01X281200Y236200D02*
Y227200D01*
G01X276800Y223000D02*
X281200D01*
G01X281300Y224800D02*
Y237200D01*
G01X288700Y224800D02*
X281300D01*
G01X288700Y237200D02*
Y224800D01*
G01X287300Y224700D02*
X281700D01*
G01X274740Y229150D02*
Y234000D01*
G01X275709Y229150D02*
X274740D01*
G01X275709Y220850D02*
Y229150D01*
G01X274740Y220850D02*
X275709D01*
G01X274740Y216000D02*
Y220850D01*
G01X276800Y236200D02*
X281200D01*
G01X281300Y237200D02*
X288700D01*
G01X292200Y282000D02*
X287800D01*
G01D02*
Y291000D01*
G01X287700Y282000D02*
X283300D01*
G01X287700Y291000D02*
Y282000D01*
G01X283300D02*
Y291000D01*
G01X287800D02*
X292200D01*
G01X283300D02*
X287700D01*
G01X294457Y-116619D02*
G03Y-112289I-51J2165D01*
G01X291853Y-116620D02*
X294456D01*
G01X291853Y-112289D02*
G03Y-116619I195J-2165D01*
G01X294165Y-118350D02*
X290701D01*
G01X294165D02*
G03X296471Y-117226I-1088J5161D01*
G01X296473Y-117625D02*
Y-117226D01*
G01X296474Y-117627D02*
G03X298494I1010J185D01*
G01X298495Y-109394D02*
Y-117625D01*
G01X301067Y-108534D02*
Y-106508D01*
G01X301615Y-108534D02*
X301067D01*
G01X301615Y-106508D02*
Y-108534D01*
G01X302461Y-106508D02*
X301615D01*
G01X302461Y-106001D02*
Y-106508D01*
G01X300223Y-106001D02*
X302461D01*
G01X300223Y-106508D02*
Y-106001D01*
G01X301067Y-106508D02*
X300223D01*
G01X305164Y-106001D02*
X304731D01*
G01X305713Y-108544D02*
X305164Y-106001D01*
G01X305171Y-108544D02*
X305713D01*
G01X304889Y-106871D02*
X305171Y-108544D01*
G01X304309D02*
X304889Y-106871D01*
G01X304086Y-108544D02*
X304309D01*
G01X303501Y-106887D02*
X304086Y-108544D01*
G01X303226D02*
X303501Y-106887D01*
G01X302698Y-108544D02*
X303226D01*
G01X303243Y-106001D02*
X302698Y-108544D01*
G01X303648Y-106001D02*
X303243D01*
G01X304192Y-107632D02*
X303648Y-106001D01*
G01X304731D02*
X304192Y-107632D01*
G01X294456Y-112288D02*
X291853D01*
G01X296473Y-110841D02*
Y-109686D01*
G01X296472Y-110841D02*
G03X292878Y-110536I-3256J-17043D01*
G01X292879Y-110535D02*
G03X290670Y-110842I280J-10112D01*
G01X298496Y-109394D02*
G03X295031Y-105933I-3962J-501D01*
G01X291563Y-105932D02*
X295031D01*
G01X291562D02*
G03X289112Y-107085I584J-4421D01*
G01Y-107086D02*
G03X289820Y-108520I585J-603D01*
G01X290987Y-107954D02*
G03X289821Y-108520I1446J-4464D01*
G01X294740Y-107954D02*
X290987D01*
G01X296473Y-109686D02*
G03X294742Y-107955I-1598J133D01*
G01X295103Y56000D02*
Y65000D01*
G01X299503D02*
Y56000D01*
G01D02*
X295103D01*
G01X300103D02*
Y65000D01*
G01X304503D02*
Y56000D01*
G01D02*
X300103D01*
G01X295103Y65000D02*
X299503D01*
G01X300103D02*
X304503D01*
G01X297500Y198300D02*
Y202700D01*
G01X306500Y198300D02*
X297500D01*
G01X297300Y190800D02*
Y198200D01*
G01X309700Y190800D02*
X297300D01*
G01Y198200D02*
X309700D01*
G01X297500Y202800D02*
Y207200D01*
G01X306500Y202800D02*
X297500D01*
G01Y207200D02*
X306500D01*
G01X297500Y202700D02*
X306500D01*
G01X292900Y215050D02*
X297400D01*
G01X292900Y220950D02*
Y215050D01*
G01X297400Y211300D02*
X309100D01*
G01X297400Y215050D02*
Y211300D01*
G01X288800Y227500D02*
Y236500D01*
G01X293200Y227500D02*
X288800D01*
G01X293200Y236500D02*
Y227500D01*
G01X293400Y224800D02*
X305100D01*
G01X293400Y230750D02*
Y224800D01*
G01X297900Y230750D02*
X293400D01*
G01Y232250D02*
X297900D01*
G01X293400Y238200D02*
Y232250D01*
G01X305100Y228550D02*
X309600D01*
G01X305100Y224800D02*
Y228550D01*
G01X297900Y232250D02*
Y230750D01*
G01X297400Y220950D02*
X292900D01*
G01X297400Y224700D02*
Y220950D01*
G01X309100Y224700D02*
X297400D01*
G01X304600Y218750D02*
X309100D01*
G01X304600Y217250D02*
Y218750D01*
G01X309100Y217250D02*
X304600D01*
G01X288800Y236500D02*
X293200D01*
G01X305100Y238200D02*
X293400D01*
G01X305100Y234450D02*
Y238200D01*
G01X309600Y234450D02*
X305100D01*
G01X292200Y291000D02*
Y282000D01*
G01X299700Y281800D02*
X292300D01*
G01D02*
Y294200D01*
G01X299700D02*
Y281800D01*
G01X307200D02*
X299800D01*
G01D02*
Y294200D01*
G01X292300D02*
X299700D01*
G01X299800D02*
X307200D01*
G01X300200Y318800D02*
Y323200D01*
G01X309200Y318800D02*
X300200D01*
G01Y332700D02*
X309200D01*
G01X300200Y328300D02*
Y332700D01*
G01X309200Y328300D02*
X300200D01*
G01Y337200D02*
X309200D01*
G01X300200Y332800D02*
Y337200D01*
G01X309200Y332800D02*
X300200D01*
G01Y323800D02*
Y328200D01*
G01X309200Y323800D02*
X300200D01*
G01Y328200D02*
X309200D01*
G01X300200Y323200D02*
X309200D01*
G01X306500Y202700D02*
Y198300D01*
G01X309700Y198200D02*
Y190800D01*
G01X306500Y207200D02*
Y202800D01*
G01X309100Y211300D02*
Y217250D01*
G01X309600Y228550D02*
Y234450D01*
G01X309100Y218750D02*
Y224700D01*
G01X322300Y283500D02*
Y292500D01*
G01X326700Y283500D02*
X322300D01*
G01X314700Y281800D02*
X307300D01*
G01D02*
Y294200D01*
G01X314700D02*
Y281800D01*
G01X307200Y294200D02*
Y281800D01*
G01X315700Y282800D02*
X321300D01*
G01X315700Y293200D02*
Y282800D01*
G01X321300D02*
Y293200D01*
G01X322300Y292500D02*
X326700D01*
G01X307300Y294200D02*
X314700D01*
G01X321300Y293200D02*
X315700D01*
G01X323200Y318300D02*
Y322700D01*
G01X332200Y318300D02*
X323200D01*
G01X309200Y323200D02*
Y318800D01*
G01Y332700D02*
Y328300D01*
G01Y337200D02*
Y332800D01*
G01X323200Y327300D02*
Y331700D01*
G01X332200Y327300D02*
X323200D01*
G01Y331700D02*
X332200D01*
G01X323200Y331800D02*
Y336200D01*
G01X332200Y331800D02*
X323200D01*
G01Y336200D02*
X332200D01*
G01X323200Y336300D02*
Y340700D01*
G01X332200Y336300D02*
X323200D01*
G01Y322800D02*
Y327200D01*
G01X332200Y322800D02*
X323200D01*
G01Y327200D02*
X332200D01*
G01X323200Y322700D02*
X332200D01*
G01X309200Y328200D02*
Y323800D01*
G01X323200Y345300D02*
Y349700D01*
G01X332200Y345300D02*
X323200D01*
G01Y349700D02*
X332200D01*
G01X323200Y340700D02*
X332200D01*
G01X323200Y340800D02*
Y345200D01*
G01X332200Y340800D02*
X323200D01*
G01Y345200D02*
X332200D01*
G01X316300Y385500D02*
Y394500D01*
G01X320700Y385500D02*
X316300D01*
G01X320700Y394500D02*
Y385500D01*
G01X314800Y372800D02*
Y385200D01*
G01X322200Y372800D02*
X314800D01*
G01X322200Y385200D02*
Y372800D01*
G01X314800Y385200D02*
X322200D01*
G01X322000Y404800D02*
Y409200D01*
G01X331000Y404800D02*
X322000D01*
G01X316300Y394500D02*
X320700D01*
G01X322000Y409200D02*
X331000D01*
G01X339500Y223300D02*
Y227700D01*
G01X348500Y223300D02*
X339500D01*
G01Y227700D02*
X348500D01*
G01X339500D02*
Y223300D01*
G01X330500Y227700D02*
X339500D01*
G01X330500Y223300D02*
Y227700D01*
G01X339500Y223300D02*
X330500D01*
G01Y218800D02*
Y223200D01*
G01X339500Y218800D02*
X330500D01*
G01X339500Y223200D02*
Y218800D01*
G01X330500Y223200D02*
X339500D01*
G01D02*
X348500D01*
G01X339500Y218800D02*
Y223200D01*
G01X348500Y218800D02*
X339500D01*
G01X331300Y248700D02*
Y257700D01*
G01X335700Y248700D02*
X331300D01*
G01X335700Y257700D02*
Y248700D01*
G01X331300Y257700D02*
X335700D01*
G01X326700Y292500D02*
Y283500D01*
G01X337200Y284000D02*
X332800D01*
G01X337200Y293000D02*
Y284000D01*
G01X332800D02*
Y293000D01*
G01X341700Y284000D02*
X337300D01*
G01D02*
Y293000D01*
G01X332800D02*
X337200D01*
G01X337300D02*
X341700D01*
G01X332200Y322700D02*
Y318300D01*
G01Y331700D02*
Y327300D01*
G01Y336200D02*
Y331800D01*
G01Y340700D02*
Y336300D01*
G01Y327200D02*
Y322800D01*
G01Y349700D02*
Y345300D01*
G01Y345200D02*
Y340800D01*
G01X331000Y409200D02*
Y404800D01*
G01X341000Y411700D02*
Y407300D01*
G01X332000D02*
Y411700D01*
G01X341000Y407300D02*
X332000D01*
G01Y411700D02*
X341000D01*
G01X349700Y140700D02*
Y128300D01*
G01D02*
X342300D01*
G01D02*
Y140700D01*
G01X354200Y140000D02*
Y131000D01*
G01D02*
X349800D01*
G01D02*
Y140000D01*
G01D02*
X354200D01*
G01X342300Y140700D02*
X349700D01*
G01X352700Y185500D02*
Y176500D01*
G01D02*
X348300D01*
G01D02*
Y185500D01*
G01D02*
X352700D01*
G01X350900Y190949D02*
Y195349D01*
G01X359900Y190949D02*
X350900D01*
G01Y195349D02*
X359900D01*
G01X350900Y190849D02*
X359900D01*
G01Y186449D02*
X350900D01*
G01D02*
Y190849D01*
G01X358300Y219300D02*
Y226700D01*
G01X370700Y219300D02*
X358300D01*
G01Y226700D02*
X370700D01*
G01X344800Y231000D02*
Y240000D01*
G01X349200Y231000D02*
X344800D01*
G01X349200Y240000D02*
Y231000D01*
G01X348500Y227700D02*
Y223300D01*
G01Y223200D02*
Y218800D01*
G01X344800Y240000D02*
X349200D01*
G01X341800Y284000D02*
Y293000D01*
G01X346200Y284000D02*
X341800D01*
G01X346200Y293000D02*
Y284000D01*
G01X346300D02*
Y293000D01*
G01X350700Y284000D02*
X346300D01*
G01X350700Y293000D02*
Y284000D01*
G01X341700Y293000D02*
Y284000D01*
G01X341800Y293000D02*
X346200D01*
G01X346300D02*
X350700D01*
G01X344000Y334800D02*
Y339200D01*
G01X353000Y334800D02*
X344000D01*
G01X353000Y339200D02*
Y334800D01*
G01X344000Y330300D02*
Y334700D01*
G01X353000Y330300D02*
X344000D01*
G01Y334700D02*
X353000D01*
G01D02*
Y330300D01*
G01X344000Y325800D02*
Y330200D01*
G01X353000Y325800D02*
X344000D01*
G01Y330200D02*
X353000D01*
G01D02*
Y325800D01*
G01X344000Y321300D02*
Y325700D01*
G01X353000Y321300D02*
X344000D01*
G01Y325700D02*
X353000D01*
G01D02*
Y321300D01*
G01X344000Y339200D02*
X353000D01*
G01X344000Y339300D02*
Y343700D01*
G01X353000Y339300D02*
X344000D01*
G01Y343700D02*
X353000D01*
G01D02*
Y339300D01*
G01X349100Y385900D02*
X359500D01*
G01X349100Y391500D02*
Y385900D01*
G01X349800Y396400D02*
X358800D01*
G01X349800Y392000D02*
Y396400D01*
G01X358800Y392000D02*
X349800D01*
G01Y401000D02*
Y405400D01*
G01X358800Y401000D02*
X349800D01*
G01Y405400D02*
X358800D01*
G01X349800Y405500D02*
Y409900D01*
G01X358800Y405500D02*
X349800D01*
G01Y396500D02*
Y400900D01*
G01X358800Y396500D02*
X349800D01*
G01Y400900D02*
X358800D01*
G01X359500Y391500D02*
X349100D01*
G01X349800Y409900D02*
X358800D01*
G01X352800Y417500D02*
Y421900D01*
G01D02*
X361800D01*
G01Y417500D02*
X352800D01*
G01X351500Y415200D02*
X360500D01*
G01X351500Y410800D02*
Y415200D01*
G01X360500Y410800D02*
X351500D01*
G01X379200Y74500D02*
X374800D01*
G01D02*
Y83500D01*
G01D02*
X379200D01*
G01X374200Y94200D02*
Y83800D01*
G01D02*
X379800D01*
G01X370300Y109700D02*
X382700D01*
G01Y102300D02*
X370300D01*
G01D02*
Y109700D01*
G01X379800Y94200D02*
X374200D01*
G01X382200Y127300D02*
X374800D01*
G01D02*
Y139700D01*
G01D02*
X382200D01*
G01X369700Y136700D02*
Y142300D01*
G01D02*
X359300D01*
G01D02*
Y136700D01*
G01D02*
X369700D01*
G01X368000Y174200D02*
X377000D01*
G01Y169800D02*
X368000D01*
G01D02*
Y174200D01*
G01X359900Y195349D02*
Y190949D01*
G01Y190849D02*
Y186449D01*
G01X358500Y214800D02*
Y219200D01*
G01X367500Y214800D02*
X358500D01*
G01X367500Y219200D02*
Y214800D01*
G01X358500Y219200D02*
X367500D01*
G01X370700Y226700D02*
Y219300D01*
G01X362500Y292300D02*
Y304700D01*
G01X369900Y292300D02*
X362500D01*
G01X369900Y304700D02*
Y292300D01*
G01X362500Y304700D02*
X369900D01*
G01X372000Y321300D02*
Y325700D01*
G01X381000Y321300D02*
X372000D01*
G01Y325700D02*
X381000D01*
G01X372000Y330200D02*
X381000D01*
G01X372000Y325800D02*
Y330200D01*
G01X381000Y325800D02*
X372000D01*
G01Y334700D02*
X381000D01*
G01X372000Y330300D02*
Y334700D01*
G01X381000Y330300D02*
X372000D01*
G01Y334800D02*
Y339200D01*
G01X381000Y334800D02*
X372000D01*
G01Y343700D02*
X381000D01*
G01X372000Y339300D02*
Y343700D01*
G01X381000Y339300D02*
X372000D01*
G01Y339200D02*
X381000D01*
G01X359500Y385900D02*
Y391500D01*
G01X358800Y396400D02*
Y392000D01*
G01Y405400D02*
Y401000D01*
G01Y409900D02*
Y405500D01*
G01Y400900D02*
Y396500D01*
G01X361800Y421900D02*
Y417500D01*
G01X360500Y415200D02*
Y410800D01*
G01X379200Y83500D02*
Y74500D01*
G01X379800Y83800D02*
Y94200D01*
G01X382700Y109700D02*
Y102300D01*
G01X394229Y127161D02*
X385229D01*
G01D02*
Y131561D01*
G01X382200Y139700D02*
Y127300D01*
G01X385229Y131561D02*
X394229D01*
G01X391248Y150997D02*
X398886D01*
G01Y154697D02*
X391248D01*
G01D02*
Y150997D01*
G01X394948Y150760D02*
X387310D01*
G01D02*
Y147060D01*
G01D02*
X394948D01*
G01X391248Y162808D02*
X398886D01*
G01X391248Y166508D02*
Y162808D01*
G01X391030Y176700D02*
Y172300D01*
G01D02*
X382030D01*
G01D02*
Y176700D01*
G01D02*
X391030D01*
G01X377000Y174200D02*
Y169800D01*
G01X394948Y178320D02*
X391248D01*
G01D02*
Y170682D01*
G01D02*
X394948D01*
G01X398886Y166508D02*
X391248D01*
G01Y198241D02*
X398886D01*
G01X391248Y201941D02*
Y198241D01*
G01Y182493D02*
X398886D01*
G01Y186193D02*
X391248D01*
G01D02*
Y182493D01*
G01X398886Y201941D02*
X391248D01*
G01X391247Y202178D02*
X398885D01*
G01X391247Y205878D02*
Y202178D01*
G01X398885Y205878D02*
X391247D01*
G01X394948Y213752D02*
X391248D01*
G01Y206114D02*
X394948D01*
G01X391248Y213752D02*
Y206114D01*
G01X387310Y213989D02*
X394948D01*
G01X387310Y217689D02*
Y213989D01*
G01X394948Y217689D02*
X387310D01*
G01X389700Y248600D02*
Y257600D01*
G01X394100Y248600D02*
X389700D01*
G01X383800D02*
Y257600D01*
G01X388200Y248600D02*
X383800D01*
G01X388200Y257600D02*
Y248600D01*
G01X377900D02*
Y257600D01*
G01X382300Y248600D02*
X377900D01*
G01X382300Y257600D02*
Y248600D01*
G01X389700Y257600D02*
X394100D01*
G01X383800D02*
X388200D01*
G01X377900D02*
X382300D01*
G01X376900Y307000D02*
Y311400D01*
G01X385900Y307000D02*
X376900D01*
G01Y311400D02*
X385900D01*
G01D02*
Y307000D01*
G01X386700D02*
Y311400D01*
G01X395700Y307000D02*
X386700D01*
G01Y311400D02*
X395700D01*
G01X381000Y325700D02*
Y321300D01*
G01Y330200D02*
Y325800D01*
G01Y334700D02*
Y330300D01*
G01Y339200D02*
Y334800D01*
G01Y343700D02*
Y339300D01*
G01X381500Y378000D02*
X390500D01*
G01X381500Y373600D02*
Y378000D01*
G01X390500Y373600D02*
X381500D01*
G01X390500Y378000D02*
Y373600D01*
G01X381500Y383200D02*
X390500D01*
G01X381500Y378800D02*
Y383200D01*
G01X390500Y378800D02*
X381500D01*
G01X390500Y383200D02*
Y378800D01*
G01X394229Y131561D02*
Y127161D01*
G01X398885Y143123D02*
Y150761D01*
G01X395185D02*
Y143123D01*
G01D02*
X398885D01*
G01X406760Y135248D02*
Y142886D01*
G01D02*
X403060D01*
G01D02*
Y135248D01*
G01D02*
X406760D01*
G01X402823Y143122D02*
Y150760D01*
G01X399123D02*
Y143122D01*
G01D02*
X402823D01*
G01X398886Y150997D02*
Y154697D01*
G01X402823Y158870D02*
Y166508D01*
G01X399123D02*
Y158870D01*
G01D02*
X402823D01*
G01X398885Y150761D02*
X395185D01*
G01X394948Y147060D02*
Y150760D01*
G01X398886Y162808D02*
Y166508D01*
G01X402823Y150760D02*
X399123D01*
G01X414635Y162571D02*
X406997D01*
G01Y158871D02*
X414635D01*
G01X406997Y162571D02*
Y158871D01*
G01X406760D02*
Y166509D01*
G01X403060D02*
Y158871D01*
G01D02*
X406760D01*
G01X406997Y154934D02*
X414635D01*
G01Y158634D02*
X406997D01*
G01D02*
Y154934D01*
G01X402823Y150997D02*
Y158635D01*
G01D02*
X399123D01*
G01D02*
Y150997D01*
G01D02*
X402823D01*
G01X410697Y150760D02*
X403059D01*
G01D02*
Y147060D01*
G01D02*
X410697D01*
G01D02*
Y150760D01*
G01X407400Y177200D02*
X416400D01*
G01X407400Y172800D02*
Y177200D01*
G01X416400Y172800D02*
X407400D01*
G01X402823Y166508D02*
X399123D01*
G01X394948Y170682D02*
Y178320D01*
G01X406760Y178556D02*
Y182256D01*
G01X399122D02*
Y178556D01*
G01D02*
X406760D01*
G01Y166509D02*
X403060D01*
G01X410697Y170445D02*
X403059D01*
G01D02*
Y166745D01*
G01D02*
X410697D01*
G01D02*
Y170445D01*
G01X403060Y190367D02*
X406760D01*
G01X403060Y198005D02*
Y190367D01*
G01X406760D02*
Y198005D01*
G01D02*
X403060D01*
G01X395185Y190367D02*
X402823D01*
G01X395185Y194067D02*
Y190367D01*
G01X402823Y194067D02*
X395185D01*
G01X402823Y190367D02*
Y194067D01*
G01X406996Y194304D02*
X414634D01*
G01X406996Y198004D02*
Y194304D01*
G01X414634Y198004D02*
X406996D01*
G01X398886Y198241D02*
Y201941D01*
G01X406760Y182256D02*
X399122D01*
G01X398886Y182493D02*
Y186193D01*
G01X398885Y202178D02*
Y205878D01*
G01X394948Y206114D02*
Y213752D01*
G01Y213989D02*
Y217689D01*
G01X400000Y223700D02*
X409000D01*
G01X400000Y219300D02*
Y223700D01*
G01X409000Y219300D02*
X400000D01*
G01X409000Y223700D02*
Y219300D01*
G01X395000Y226300D02*
X412000D01*
G01X395000Y238700D02*
Y226300D01*
G01X401500Y248600D02*
Y257600D01*
G01X405900Y248600D02*
X401500D01*
G01X405900Y257600D02*
Y248600D01*
G01X395600D02*
Y257600D01*
G01X400000Y248600D02*
X395600D01*
G01X400000Y257600D02*
Y248600D01*
G01X394100Y257600D02*
Y248600D01*
G01X407100D02*
Y257600D01*
G01X411500Y248600D02*
X407100D01*
G01X412000Y238700D02*
X395000D01*
G01X401500Y257600D02*
X405900D01*
G01X395600D02*
X400000D01*
G01X407100D02*
X411500D01*
G01X410500Y281800D02*
Y289200D01*
G01X422900Y281800D02*
X410500D01*
G01Y297300D02*
X422900D01*
G01X410500Y289900D02*
Y297300D01*
G01X422900Y289900D02*
X410500D01*
G01Y289200D02*
X422900D01*
G01X395700Y311400D02*
Y307000D01*
G01X394900Y321700D02*
Y326100D01*
G01X403900Y321700D02*
X394900D01*
G01Y326100D02*
X403900D01*
G01D02*
Y321700D01*
G01X394900Y326900D02*
Y331300D01*
G01X403900Y326900D02*
X394900D01*
G01Y331300D02*
X403900D01*
G01D02*
Y326900D01*
G01X400200Y340500D02*
X395800D01*
G01X400200Y349500D02*
Y340500D01*
G01X395800Y349500D02*
X400200D01*
G01X395800Y340500D02*
Y349500D01*
G01X424500Y70800D02*
Y75200D01*
G01X433500Y70800D02*
X424500D01*
G01Y75200D02*
X433500D01*
G01X424200Y75300D02*
X429800D01*
G01X424200Y85700D02*
Y75300D01*
G01X429700Y89500D02*
X425300D01*
G01D02*
Y98500D01*
G01X429800Y85700D02*
X424200D01*
G01X425300Y98500D02*
X429700D01*
G01X418808Y139185D02*
X422508D01*
G01X418808Y146823D02*
Y139185D01*
G01X422508D02*
Y146823D01*
G01Y158870D02*
Y166508D01*
G01X418808Y158870D02*
X422508D01*
G01X418808Y166508D02*
Y158870D01*
G01X410933Y147060D02*
X418571D01*
G01X410933Y150760D02*
Y147060D01*
G01X418571Y150760D02*
X410933D01*
G01X418571Y147060D02*
Y150760D01*
G01X410933Y150997D02*
X418571D01*
G01X410933Y154697D02*
Y150997D01*
G01X418571Y154697D02*
X410933D01*
G01X418571Y150997D02*
Y154697D01*
G01X422508Y146823D02*
X418808D01*
G01X422508Y154697D02*
X418808D01*
G01X422508Y147059D02*
Y154697D01*
G01X418808Y147059D02*
X422508D01*
G01X418808Y154697D02*
Y147059D01*
G01X422745Y158871D02*
X426445D01*
G01X422745Y166509D02*
Y158871D01*
G01X426445D02*
Y166509D01*
G01X414871Y162808D02*
X418571D01*
G01X414871Y170446D02*
Y162808D01*
G01X418571D02*
Y170446D01*
G01X418808Y158634D02*
Y154934D01*
G01X426446Y158634D02*
X418808D01*
G01X426446Y154934D02*
Y158634D01*
G01X418808Y154934D02*
X426446D01*
G01X414871Y154933D02*
X418571D01*
G01X414871Y162571D02*
Y154933D01*
G01X418571Y162571D02*
X414871D01*
G01X418571Y154933D02*
Y162571D01*
G01X410934Y170445D02*
Y162807D01*
G01D02*
X414634D01*
G01D02*
Y170445D01*
G01X414635Y158871D02*
Y162571D01*
G01Y154934D02*
Y158634D01*
G01X416400Y177200D02*
Y172800D01*
G01X417500Y177200D02*
X426500D01*
G01X417500Y172800D02*
Y177200D01*
G01X426500Y172800D02*
X417500D01*
G01X426500Y177200D02*
Y172800D01*
G01X422508Y166508D02*
X418808D01*
G01X426445Y178556D02*
Y182256D01*
G01X418807Y178556D02*
X426445D01*
G01X418807Y182256D02*
Y178556D01*
G01X426445Y166509D02*
X422745D01*
G01X418571Y170446D02*
X414871D01*
G01X426445Y166745D02*
Y170445D01*
G01X418807Y166745D02*
X426445D01*
G01X418807Y170445D02*
Y166745D01*
G01X426445Y170445D02*
X418807D01*
G01X414634D02*
X410934D01*
G01X432200Y196300D02*
X427800D01*
G01D02*
Y205300D01*
G01X426445Y182256D02*
X418807D01*
G01X418808Y182493D02*
X422508D01*
G01X418808Y190131D02*
Y182493D01*
G01X422508Y190131D02*
X418808D01*
G01X422508Y182493D02*
Y190131D01*
G01X414871Y194304D02*
X418571D01*
G01X414871Y201942D02*
Y194304D01*
G01X418571D02*
Y201942D01*
G01X414634Y194304D02*
Y198004D01*
G01X427800Y205300D02*
X432200D01*
G01X422745Y210052D02*
X426445D01*
G01X422745Y217690D02*
Y210052D01*
G01X426445D02*
Y217690D01*
G01X418571Y201942D02*
X414871D01*
G01X410934Y205878D02*
Y202178D01*
G01X418572Y205878D02*
X410934D01*
G01Y202178D02*
X418572D01*
G01D02*
Y205878D01*
G01X412000Y226300D02*
Y238700D01*
G01X426445Y217690D02*
X422745D01*
G01X411500Y257600D02*
Y248600D01*
G01X418700D02*
Y257600D01*
G01X423100Y248600D02*
X418700D01*
G01X423100Y257600D02*
Y248600D01*
G01X412800D02*
Y257600D01*
G01X417200Y248600D02*
X412800D01*
G01X417200Y257600D02*
Y248600D01*
G01X418700Y257600D02*
X423100D01*
G01X412800D02*
X417200D01*
G01X422900Y289200D02*
Y281800D01*
G01Y297300D02*
Y289900D01*
G01X419200Y340500D02*
X414800D01*
G01Y349500D02*
X419200D01*
G01X414800Y340500D02*
Y349500D01*
G01X419200D02*
Y340500D01*
G01X426200Y391700D02*
X421800D01*
G01X426200Y400700D02*
Y391700D01*
G01X421800Y400700D02*
X426200D01*
G01X421800Y391700D02*
Y400700D01*
G01X420000Y404300D02*
Y408700D01*
G01X429000Y404300D02*
X420000D01*
G01Y408700D02*
X429000D01*
G01X420000Y409300D02*
Y413700D01*
G01X429000Y409300D02*
X420000D01*
G01Y413700D02*
X429000D01*
G01X433500Y75200D02*
Y70800D01*
G01X429800Y75300D02*
Y85700D01*
G01X434200Y89500D02*
X429800D01*
G01X434200Y98500D02*
Y89500D01*
G01X429800D02*
Y98500D01*
G01X429700D02*
Y89500D01*
G01X429800Y98500D02*
X434200D01*
G01X439300Y105500D02*
Y114500D01*
G01X443700Y105500D02*
X439300D01*
G01X443700Y114500D02*
Y105500D01*
G01X434800D02*
Y114500D01*
G01X439200Y105500D02*
X434800D01*
G01X439200Y114500D02*
Y105500D01*
G01X439300Y114500D02*
X443700D01*
G01X434800D02*
X439200D01*
G01X438493Y131311D02*
X442193D01*
G01X438493Y138949D02*
Y131311D01*
G01X442193Y138949D02*
X438493D01*
G01X442193Y131311D02*
Y138949D01*
G01X442430Y139185D02*
X446130D01*
G01X442430Y146823D02*
Y139185D01*
G01X434556Y143123D02*
X438256D01*
G01X434556Y150761D02*
Y143123D01*
G01X438256D02*
Y150761D01*
G01X429050Y142681D02*
X432750D01*
G01X429050Y150319D02*
Y142681D01*
G01X432750D02*
Y150319D01*
G01X428300Y162500D02*
Y171500D01*
G01X432700Y162500D02*
X428300D01*
G01X432700Y171500D02*
Y162500D01*
G01Y152500D02*
X428300D01*
G01X432700Y161500D02*
Y152500D01*
G01X428300Y161500D02*
X432700D01*
G01X428300Y152500D02*
Y161500D01*
G01X442193Y154933D02*
Y162571D01*
G01X438493Y154933D02*
X442193D01*
G01X438493Y162571D02*
Y154933D01*
G01X442193Y162571D02*
X438493D01*
G01X442430Y166508D02*
Y162808D01*
G01D02*
X450068D01*
G01X442430Y154934D02*
X446130D01*
G01X442430Y162572D02*
Y154934D01*
G01X446130Y162572D02*
X442430D01*
G01X442193Y162807D02*
Y170445D01*
G01X438493Y162807D02*
X442193D01*
G01X438493Y170445D02*
Y162807D01*
G01X434556Y158871D02*
X438256D01*
G01X434556Y166509D02*
Y158871D01*
G01X438256D02*
Y166509D01*
G01X446130Y146823D02*
X442430D01*
G01X438256Y150761D02*
X434556D01*
G01X438256Y158634D02*
X434556D01*
G01Y150996D02*
X438256D01*
G01X434556Y158634D02*
Y150996D01*
G01X438256D02*
Y158634D01*
G01X432750Y150319D02*
X429050D01*
G01X428300Y171500D02*
X432700D01*
G01X429900Y176300D02*
X438900D01*
G01X429900Y171900D02*
Y176300D01*
G01X438900Y171900D02*
X429900D01*
G01X438900Y176300D02*
Y171900D01*
G01X428400Y177100D02*
Y186100D01*
G01X432800Y177100D02*
X428400D01*
G01X432800Y186100D02*
Y177100D01*
G01X439911Y173300D02*
Y177700D01*
G01X448911Y173300D02*
X439911D01*
G01Y177700D02*
X448911D01*
G01X442430Y170445D02*
Y166745D01*
G01X450068Y170445D02*
X442430D01*
G01Y166745D02*
X450068D01*
G01Y166508D02*
X442430D01*
G01X442193Y170445D02*
X438493D01*
G01X434556Y182256D02*
Y178556D01*
G01D02*
X442194D01*
G01D02*
Y182256D01*
G01X438256Y166509D02*
X434556D01*
G01X442430Y178555D02*
X446130D01*
G01X442430Y186193D02*
Y178555D01*
G01X428400Y186100D02*
X432800D01*
G01X432200Y205300D02*
Y196300D01*
G01X438492Y190367D02*
X446130D01*
G01X438492Y194067D02*
Y190367D01*
G01X446130Y194067D02*
X438492D01*
G01X442194Y182256D02*
X434556D01*
G01X429156Y187930D02*
X432856D01*
G01X429156Y195568D02*
Y187930D01*
G01X432856Y195568D02*
X429156D01*
G01X432856Y187930D02*
Y195568D01*
G01X446130Y186193D02*
X442430D01*
G01X438493Y213989D02*
X442193D01*
G01X438493Y221627D02*
Y213989D01*
G01X442193D02*
Y221627D01*
G01X443085Y224200D02*
X452085D01*
G01X443085Y219800D02*
Y224200D01*
G01X452085Y219800D02*
X443085D01*
G01X442193Y221627D02*
X438493D01*
G01X437200Y239500D02*
X432800D01*
G01Y248500D02*
X437200D01*
G01X432800Y239500D02*
Y248500D01*
G01X437200D02*
Y239500D01*
G01X446200D02*
X441800D01*
G01Y248500D02*
X446200D01*
G01X441800Y239500D02*
Y248500D01*
G01X437300D02*
X441700D01*
G01X437300Y239500D02*
Y248500D01*
G01X441700Y239500D02*
X437300D01*
G01X441700Y248500D02*
Y239500D01*
G01X430000Y295300D02*
Y299700D01*
G01X439000Y295300D02*
X430000D01*
G01Y299700D02*
X439000D01*
G01D02*
Y295300D01*
G01X433000Y388700D02*
X442000D01*
G01X433000Y384300D02*
Y388700D01*
G01X442000Y384300D02*
X433000D01*
G01X442000Y388700D02*
Y384300D01*
G01X433000Y394300D02*
Y398700D01*
G01X442000Y394300D02*
X433000D01*
G01Y398700D02*
X442000D01*
G01D02*
Y394300D01*
G01X433000Y404300D02*
Y408700D01*
G01X442000Y404300D02*
X433000D01*
G01X442000Y408700D02*
Y404300D01*
G01X429000Y408700D02*
Y404300D01*
G01X433000Y413700D02*
X442000D01*
G01X433000Y409300D02*
Y413700D01*
G01X442000Y409300D02*
X433000D01*
G01X442000Y413700D02*
Y409300D01*
G01X433000Y408700D02*
X442000D01*
G01X429000Y413700D02*
Y409300D01*
G01X450800Y120500D02*
X455200D01*
G01X450800Y111500D02*
Y120500D01*
G01X455200Y111500D02*
X450800D01*
G01X455200Y120500D02*
Y111500D01*
G01X456300Y120500D02*
X460700D01*
G01X456300Y111500D02*
Y120500D01*
G01X460700Y111500D02*
X456300D01*
G01X460700Y120500D02*
Y111500D01*
G01X458177Y131074D02*
Y127374D01*
G01D02*
X465815D01*
G01X450304Y135247D02*
X454004D01*
G01X450304Y142885D02*
Y135247D01*
G01X454004Y142885D02*
X450304D01*
G01X454004Y135247D02*
Y142885D01*
G01X461878Y139185D02*
Y142885D01*
G01X454240Y139185D02*
X461878D01*
G01X454240Y142885D02*
Y139185D01*
G01X461878Y142885D02*
X454240D01*
G01X446130Y139185D02*
Y146823D01*
G01X465815Y131074D02*
X458177D01*
G01X446367Y143123D02*
X454005D01*
G01X446367Y146823D02*
Y143123D01*
G01X454005D02*
Y146823D01*
G01X458178Y150997D02*
X461878D01*
G01X458178Y158635D02*
Y150997D01*
G01X461878Y158635D02*
X458178D01*
G01X461878Y150997D02*
Y158635D01*
G01X450304Y162807D02*
X454004D01*
G01X450304Y170445D02*
Y162807D01*
G01X454004D02*
Y170445D01*
G01X450067Y154933D02*
Y162571D01*
G01X446367Y154933D02*
X450067D01*
G01X446367Y162571D02*
Y154933D01*
G01X450067Y162571D02*
X446367D01*
G01X450068Y162808D02*
Y166508D01*
G01X446130Y154934D02*
Y162572D01*
G01X462114Y154934D02*
X469752D01*
G01X462114Y158634D02*
Y154934D01*
G01X469752Y158634D02*
X462114D01*
G01X454005Y146823D02*
X446367D01*
G01X448911Y173300D02*
Y177700D01*
G01X457911Y173300D02*
X448911D01*
G01Y177700D02*
X457911D01*
G01D02*
Y173300D01*
G01X461500Y177700D02*
X470500D01*
G01X461500Y173300D02*
Y177700D01*
G01X470500Y173300D02*
X461500D01*
G01X448911Y177700D02*
Y173300D01*
G01X450068Y166745D02*
Y170445D01*
G01X454004D02*
X450304D01*
G01X458177Y166745D02*
X465815D01*
G01X458177Y170445D02*
Y166745D01*
G01X465815Y170445D02*
X458177D01*
G01X462115Y182256D02*
Y178556D01*
G01D02*
X469753D01*
G01X450304D02*
X454004D01*
G01X450304Y186194D02*
Y178556D01*
G01X454004D02*
Y186194D01*
G01X446130Y178555D02*
Y186193D01*
G01X446367Y178555D02*
X450067D01*
G01X446367Y186193D02*
Y178555D01*
G01X450067D02*
Y186193D01*
G01X458178Y198004D02*
Y194304D01*
G01D02*
X465816D01*
G01Y198004D02*
X458178D01*
G01Y194067D02*
Y190367D01*
G01X465816Y194067D02*
X458178D01*
G01Y190367D02*
X465816D01*
G01X462115Y182493D02*
X465815D01*
G01X462115Y190131D02*
Y182493D01*
G01X465815Y190131D02*
X462115D01*
G01X446366Y190366D02*
X450066D01*
G01X446366Y198004D02*
Y190366D01*
G01X450066D02*
Y198004D01*
G01D02*
X446366D01*
G01X446130Y190367D02*
Y194067D01*
G01X469753Y182256D02*
X462115D01*
G01X454004Y186194D02*
X450304D01*
G01X450067Y186193D02*
X446367D01*
G01X461878Y182493D02*
Y186193D01*
G01X454240Y182493D02*
X461878D01*
G01X454240Y186193D02*
Y182493D01*
G01X461878Y186193D02*
X454240D01*
G01X454241Y190130D02*
Y186430D01*
G01X461879Y190130D02*
X454241D01*
G01X461879Y186430D02*
Y190130D01*
G01X454241Y186430D02*
X461879D01*
G01X446366Y206115D02*
X454004D01*
G01X446366Y209815D02*
Y206115D01*
G01X454004Y209815D02*
X446366D01*
G01X454004Y206115D02*
Y209815D01*
G01X452085Y224200D02*
Y219800D01*
G01X446200Y248500D02*
Y239500D01*
G01X459800Y248500D02*
X464200D01*
G01X459800Y239500D02*
Y248500D01*
G01X464200Y239500D02*
X459800D01*
G01X459700D02*
X455300D01*
G01X459700Y248500D02*
Y239500D01*
G01X455300Y248500D02*
X459700D01*
G01X455300Y239500D02*
Y248500D01*
G01X450700Y239500D02*
X446300D01*
G01X450700Y248500D02*
Y239500D01*
G01X446300Y248500D02*
X450700D01*
G01X446300Y239500D02*
Y248500D01*
G01X450800D02*
X455200D01*
G01X450800Y239500D02*
Y248500D01*
G01X455200Y239500D02*
X450800D01*
G01X455200Y248500D02*
Y239500D01*
G01X450000Y282300D02*
Y286700D01*
G01X459000Y282300D02*
X450000D01*
G01X459000Y286700D02*
Y282300D01*
G01X450000Y281700D02*
X459000D01*
G01X450000Y277300D02*
Y281700D01*
G01X459000Y277300D02*
X450000D01*
G01X459000Y281700D02*
Y277300D01*
G01X450000Y286700D02*
X459000D01*
G01X450000Y287300D02*
Y291700D01*
G01X459000Y287300D02*
X450000D01*
G01Y291700D02*
X459000D01*
G01D02*
Y287300D01*
G01X450000Y296700D02*
X459000D01*
G01X450000Y292300D02*
Y296700D01*
G01X459000Y292300D02*
X450000D01*
G01X459000Y296700D02*
Y292300D01*
G01Y387300D02*
Y391700D01*
G01X468000Y387300D02*
X459000D01*
G01Y396200D02*
X468000D01*
G01X459000Y391800D02*
Y396200D01*
G01X468000Y391800D02*
X459000D01*
G01Y391700D02*
X468000D01*
G01X467000Y89300D02*
Y93700D01*
G01X476000Y89300D02*
X467000D01*
G01Y93700D02*
X476000D01*
G01D02*
Y89300D01*
G01X467000Y94300D02*
Y98700D01*
G01X476000Y94300D02*
X467000D01*
G01Y98700D02*
X476000D01*
G01D02*
Y94300D01*
G01X465815Y127374D02*
Y131074D01*
G01X478516Y144655D02*
X474816D01*
G01X478516Y137017D02*
Y144655D01*
G01X474816Y137017D02*
X478516D01*
G01X474816Y144655D02*
Y137017D01*
G01X469752Y154934D02*
Y158634D01*
G01X475800Y179711D02*
Y188711D01*
G01X480200Y179711D02*
X475800D01*
G01X480200Y188711D02*
Y179711D01*
G01X470500Y177700D02*
Y173300D01*
G01X465815Y166745D02*
Y170445D01*
G01X469753Y178556D02*
Y182256D01*
G01X466051Y166745D02*
X473689D01*
G01X466051Y170445D02*
Y166745D01*
G01X473689Y170445D02*
X466051D01*
G01X473689Y166745D02*
Y170445D01*
G01X475800Y188711D02*
X480200D01*
G01X465816Y194304D02*
Y198004D01*
G01Y190367D02*
Y194067D01*
G01X465815Y182493D02*
Y190131D01*
G01X469989Y201941D02*
Y198241D01*
G01D02*
X477627D01*
G01D02*
Y201941D01*
G01X466052Y182493D02*
X469752D01*
G01X466052Y190131D02*
Y182493D01*
G01X469752Y190131D02*
X466052D01*
G01X469752Y182493D02*
Y190131D01*
G01X466052Y210052D02*
X469752D01*
G01X466052Y217690D02*
Y210052D01*
G01X469752D02*
Y217690D01*
G01X477627Y201941D02*
X469989D01*
G01Y210052D02*
X473689D01*
G01X469989Y217690D02*
Y210052D01*
G01X473689D02*
Y217690D01*
G01X466052Y209815D02*
Y206115D01*
G01X473690Y209815D02*
X466052D01*
G01Y206115D02*
X473690D01*
G01D02*
Y209815D01*
G01X469752Y217690D02*
X466052D01*
G01X473689D02*
X469989D01*
G01X464200Y248500D02*
Y239500D01*
G01X480200Y357300D02*
Y352900D01*
G01X471200D02*
Y357300D01*
G01X480200Y352900D02*
X471200D01*
G01Y357300D02*
X480200D01*
G01X468000Y391700D02*
Y387300D01*
G01Y396200D02*
Y391800D01*
G01X490400Y122600D02*
Y130000D01*
G01X502800Y122600D02*
X490400D01*
G01Y130000D02*
X502800D01*
G01X486000Y160800D02*
Y165200D01*
G01X495000Y160800D02*
X486000D01*
G01X495000Y165200D02*
Y160800D01*
G01X486000Y165200D02*
X495000D01*
G01X486000Y165300D02*
Y169700D01*
G01X495000Y165300D02*
X486000D01*
G01Y169700D02*
X495000D01*
G01D02*
Y165300D01*
G01X486000Y174300D02*
Y178700D01*
G01X495000Y174300D02*
X486000D01*
G01Y178700D02*
X495000D01*
G01D02*
Y174300D01*
G01X486000Y178800D02*
Y183200D01*
G01X495000Y178800D02*
X486000D01*
G01X495000Y183200D02*
Y178800D01*
G01X486000Y195300D02*
Y199700D01*
G01X495000Y195300D02*
X486000D01*
G01X495000Y199700D02*
Y195300D01*
G01X486000Y183200D02*
X495000D01*
G01X486000Y187700D02*
X495000D01*
G01X486000Y183300D02*
Y187700D01*
G01X495000Y183300D02*
X486000D01*
G01X495000Y187700D02*
Y183300D01*
G01X486000Y199700D02*
X495000D01*
G01X486000Y200300D02*
Y204700D01*
G01X495000Y200300D02*
X486000D01*
G01Y204700D02*
X495000D01*
G01D02*
Y200300D01*
G01X498300Y266200D02*
X493900D01*
G01D02*
Y275200D01*
G01D02*
X498300D01*
G01X490700Y348000D02*
X486300D01*
G01D02*
Y357000D01*
G01X490700D02*
Y348000D01*
G01X500700D02*
X496300D01*
G01D02*
Y357000D01*
G01X496500Y343300D02*
Y347700D01*
G01X505500Y343300D02*
X496500D01*
G01Y347700D02*
X505500D01*
G01X495700Y348000D02*
X491300D01*
G01X495700Y357000D02*
Y348000D01*
G01X491300D02*
Y357000D01*
G01X486300D02*
X490700D01*
G01X496300D02*
X500700D01*
G01X491300D02*
X495700D01*
G01X502800Y130000D02*
Y122600D01*
G01X498500Y241700D02*
Y249100D01*
G01X510900Y241700D02*
X498500D01*
G01Y249100D02*
X510900D01*
G01D02*
Y241700D01*
G01X498300Y275200D02*
Y266200D01*
G01X500700Y357000D02*
Y348000D01*
G01X505500Y347700D02*
Y343300D01*
G01X506300Y383000D02*
Y392000D01*
G01X510700Y383000D02*
X506300D01*
G01X510700Y392000D02*
Y383000D01*
G01X501300D02*
Y392000D01*
G01X505700Y383000D02*
X501300D01*
G01X505700Y392000D02*
Y383000D01*
G01X506300Y392000D02*
X510700D01*
G01X501300D02*
X505700D01*
G01X530000Y258700D02*
X525600D01*
G01X530000Y267700D02*
Y258700D01*
G01X525600D02*
Y267700D01*
G01D02*
X530000D01*
G01X522824Y374651D02*
Y346749D01*
G01D02*
X540376D01*
G01Y374651D02*
X522824D01*
G01X529500Y413501D02*
X525100D01*
G01X529500Y422501D02*
Y413501D01*
G01X525100Y422501D02*
X529500D01*
G01X525100Y413501D02*
Y422501D01*
G01X530100D02*
X534500D01*
G01X530100Y413501D02*
Y422501D01*
G01X534500Y413501D02*
X530100D01*
G01X538000Y66800D02*
Y71200D01*
G01X547000Y66800D02*
X538000D01*
G01Y71200D02*
X547000D01*
G01D02*
Y66800D01*
G01X538000Y66200D02*
X547000D01*
G01X538000Y61800D02*
Y66200D01*
G01X547000Y61800D02*
X538000D01*
G01X547000Y66200D02*
Y61800D01*
G01X536800Y158000D02*
Y167000D01*
G01X541200Y158000D02*
X536800D01*
G01X541200Y167000D02*
Y158000D01*
G01X536800Y167000D02*
X541200D01*
G01X543700Y175800D02*
X536300D01*
G01D02*
Y188200D01*
G01X543700D02*
Y175800D01*
G01X536300Y188200D02*
X543700D01*
G01X548800Y209000D02*
X553200D01*
G01X548800Y200000D02*
Y209000D01*
G01X553200Y200000D02*
X548800D01*
G01Y210500D02*
Y219500D01*
G01X553200Y210500D02*
X548800D01*
G01X536500Y225300D02*
Y229700D01*
G01X545500Y225300D02*
X536500D01*
G01Y229700D02*
X545500D01*
G01D02*
Y225300D01*
G01X548800Y230000D02*
Y239000D01*
G01X553200Y230000D02*
X548800D01*
G01X544300D02*
Y239000D01*
G01X548700Y230000D02*
X544300D01*
G01X548700Y239000D02*
Y230000D01*
G01X548800Y219500D02*
X553200D01*
G01X548800Y239000D02*
X553200D01*
G01X544300D02*
X548700D01*
G01X547450Y261350D02*
X543050D01*
G01X547450Y270350D02*
Y261350D01*
G01X543050D02*
Y270350D01*
G01X548000Y266200D02*
X557000D01*
G01X548000Y261800D02*
Y266200D01*
G01X557000Y261800D02*
X548000D01*
G01Y261700D02*
X557000D01*
G01X548000Y257300D02*
Y261700D01*
G01X557000Y257300D02*
X548000D01*
G01X543050Y270350D02*
X547450D01*
G01X543000Y283700D02*
X547400D01*
G01X543000Y274700D02*
Y283700D01*
G01X547400Y274700D02*
X543000D01*
G01X547400Y283700D02*
Y274700D01*
G01X547800Y274300D02*
X556800D01*
G01X547800Y269900D02*
Y274300D01*
G01X556800Y269900D02*
X547800D01*
G01X548000Y279200D02*
X557000D01*
G01X548000Y274800D02*
Y279200D01*
G01X557000Y274800D02*
X548000D01*
G01Y283700D02*
X557000D01*
G01X548000Y279300D02*
Y283700D01*
G01X557000Y279300D02*
X548000D01*
G01X543000Y284800D02*
Y289200D01*
G01X552000Y284800D02*
X543000D01*
G01Y298850D02*
X547400D01*
G01X543000Y289850D02*
Y298850D01*
G01X547400Y289850D02*
X543000D01*
G01X547400Y298850D02*
Y289850D01*
G01X543000Y299500D02*
Y308500D01*
G01X547400Y299500D02*
X543000D01*
G01X547400Y308500D02*
Y299500D01*
G01X547800Y294450D02*
X556800D01*
G01X547800Y290050D02*
Y294450D01*
G01X556800Y290050D02*
X547800D01*
G01X548000Y299800D02*
Y304200D01*
G01X557000Y299800D02*
X548000D01*
G01X543000Y289200D02*
X552000D01*
G01X543200Y316900D02*
Y324300D01*
G01X555600Y316900D02*
X543200D01*
G01X543000Y308500D02*
X547400D01*
G01X548000Y304200D02*
X557000D01*
G01X548000Y308700D02*
X557000D01*
G01X548000Y304300D02*
Y308700D01*
G01X557000Y304300D02*
X548000D01*
G01X543600Y332700D02*
Y340100D01*
G01X556000Y332700D02*
X543600D01*
G01Y332500D02*
X556000D01*
G01X543600Y325100D02*
Y332500D01*
G01X556000Y325100D02*
X543600D01*
G01X543200Y324300D02*
X555600D01*
G01X543600Y347800D02*
X556000D01*
G01X543600Y340400D02*
Y347800D01*
G01X556000Y340400D02*
X543600D01*
G01Y340100D02*
X556000D01*
G01X540376Y346749D02*
Y374651D01*
G01X538541Y345497D02*
Y340497D01*
G01X541041Y342997D02*
X536041D01*
G01X545700Y410000D02*
X541300D01*
G01X545700Y419000D02*
Y410000D01*
G01X541300Y419000D02*
X545700D01*
G01X541300Y410000D02*
Y419000D01*
G01Y419500D02*
Y428500D01*
G01X545700Y419500D02*
X541300D01*
G01X545700Y428500D02*
Y419500D01*
G01X534500Y422501D02*
Y413501D01*
G01X541300Y428500D02*
X545700D01*
G01X557700Y58400D02*
X553300D01*
G01X557700Y67400D02*
Y58400D01*
G01X553300D02*
Y67400D01*
G01X553500Y68100D02*
Y77100D01*
G01X557900Y68100D02*
X553500D01*
G01X557900Y77100D02*
Y68100D01*
G01X553300Y67400D02*
X557700D01*
G01X553500Y77100D02*
X557900D01*
G01X556500Y195800D02*
Y200200D01*
G01X565500Y195800D02*
X556500D01*
G01X565500Y200200D02*
Y195800D01*
G01X565800Y195300D02*
Y202700D01*
G01X578200Y195300D02*
X565800D01*
G01X553200Y209000D02*
Y200000D01*
G01X556500Y200200D02*
X565500D01*
G01X553200Y219500D02*
Y210500D01*
G01X565800Y202700D02*
X578200D01*
G01X566250Y231857D02*
Y237143D01*
G01X562750Y231857D02*
X566250D01*
G01X562750Y237143D02*
Y231857D01*
G01X562200Y230000D02*
X557800D01*
G01D02*
Y239000D01*
G01X562200D02*
Y230000D01*
G01X557700D02*
X553300D01*
G01X557700Y239000D02*
Y230000D01*
G01X553300D02*
Y239000D01*
G01X553200D02*
Y230000D01*
G01X567200Y229300D02*
X572800D01*
G01X567200Y239700D02*
Y229300D01*
G01X566250Y237143D02*
X562750D01*
G01X557800Y239000D02*
X562200D01*
G01X553300D02*
X557700D01*
G01X572800Y239700D02*
X567200D01*
G01X564600Y259900D02*
X578000D01*
G01X564600Y276300D02*
Y259900D01*
G01X557000Y266200D02*
Y261800D01*
G01Y261700D02*
Y257300D01*
G01X578000Y276300D02*
X564600D01*
G01X556800Y274300D02*
Y269900D01*
G01X557000Y279200D02*
Y274800D01*
G01Y283700D02*
Y279300D01*
G01X552000Y289200D02*
Y284800D01*
G01X564100Y288400D02*
X577500D01*
G01X564100Y304800D02*
Y288400D01*
G01X556800Y294450D02*
Y290050D01*
G01X557000Y304200D02*
Y299800D01*
G01X577500Y304800D02*
X564100D01*
G01X555600Y324300D02*
Y316900D01*
G01X557000Y308700D02*
Y304300D01*
G01X556000Y340100D02*
Y332700D01*
G01Y332500D02*
Y325100D01*
G01Y347800D02*
Y340400D01*
G01X550500Y404800D02*
Y409200D01*
G01X559500Y404800D02*
X550500D01*
G01X559500Y409200D02*
Y404800D01*
G01X565300Y406000D02*
Y415000D01*
G01X569700Y406000D02*
X565300D01*
G01X564800Y419500D02*
Y428500D01*
G01X569200Y419500D02*
X564800D01*
G01X553300D02*
Y428500D01*
G01X557700Y419500D02*
X553300D01*
G01X557700Y428500D02*
Y419500D01*
G01X550500Y409200D02*
X559500D01*
G01X550500Y409300D02*
Y413700D01*
G01X559500Y409300D02*
X550500D01*
G01Y413700D02*
X559500D01*
G01D02*
Y409300D01*
G01X565300Y415000D02*
X569700D01*
G01X564800Y428500D02*
X569200D01*
G01X553300D02*
X557700D01*
G01X584700Y73000D02*
X580300D01*
G01X584700Y82000D02*
Y73000D01*
G01X580300D02*
Y82000D01*
G01X575300Y73000D02*
Y82000D01*
G01X579700Y73000D02*
X575300D01*
G01X579700Y82000D02*
Y73000D01*
G01X575000Y72400D02*
X579400D01*
G01X575000Y63400D02*
Y72400D01*
G01X579400Y63400D02*
X575000D01*
G01X579400Y72400D02*
Y63400D01*
G01X580300Y82000D02*
X584700D01*
G01X575300D02*
X579700D01*
G01X578200Y202700D02*
Y195300D01*
G01X573200Y230000D02*
Y239000D01*
G01X577600Y230000D02*
X573200D01*
G01X577600Y239000D02*
Y230000D01*
G01X572800Y229300D02*
Y239700D01*
G01X573200Y239000D02*
X577600D01*
G01X578000Y259900D02*
Y276300D01*
G01X577500Y288400D02*
Y304800D01*
G01X569600Y388500D02*
Y392900D01*
G01X578600Y388500D02*
X569600D01*
G01X578600Y392900D02*
Y388500D01*
G01X569600Y383500D02*
Y387900D01*
G01X578600Y383500D02*
X569600D01*
G01Y387900D02*
X578600D01*
G01D02*
Y383500D01*
G01X569600Y392900D02*
X578600D01*
G01X574500Y405300D02*
Y409700D01*
G01X583500Y405300D02*
X574500D01*
G01X583500Y409700D02*
Y405300D01*
G01X569700Y415000D02*
Y406000D01*
G01X576800Y419500D02*
Y428500D01*
G01X581200Y419500D02*
X576800D01*
G01X581200Y428500D02*
Y419500D01*
G01X569200Y428500D02*
Y419500D01*
G01X574500Y409800D02*
Y414200D01*
G01X583500Y409800D02*
X574500D01*
G01Y414200D02*
X583500D01*
G01D02*
Y409800D01*
G01X574500Y409700D02*
X583500D01*
G01X576800Y428500D02*
X581200D01*
G01X595800Y139500D02*
Y148500D01*
G01X600200Y139500D02*
X595800D01*
G01X600200Y148500D02*
Y139500D01*
G01X595800Y148500D02*
X600200D01*
G01X595800Y160500D02*
X600200D01*
G01X595800Y151500D02*
Y160500D01*
G01X600200Y151500D02*
X595800D01*
G01X600200Y160500D02*
Y151500D01*
G01X595800Y161000D02*
Y170000D01*
G01X600200Y161000D02*
X595800D01*
G01X600200Y170000D02*
Y161000D01*
G01X595800Y170000D02*
X600200D01*
G01X595800Y171500D02*
Y180500D01*
G01X600200Y171500D02*
X595800D01*
G01X600200Y180500D02*
Y171500D01*
G01X595800Y180500D02*
X600200D01*
G01X594102Y188465D02*
X589702D01*
G01Y197465D02*
X594102D01*
G01X589702Y188465D02*
Y197465D01*
G01X594102D02*
Y188465D01*
G01X594702Y197465D02*
X599102D01*
G01X594702Y188465D02*
Y197465D01*
G01X599102Y188465D02*
X594702D01*
G01X599102Y197465D02*
Y188465D01*
G01X599702Y197465D02*
X604102D01*
G01X599702Y188465D02*
Y197465D01*
G01X604102Y188465D02*
X599702D01*
G01X606000Y259300D02*
X597000D01*
G01D02*
Y263700D01*
G01D02*
X606000D01*
G01X597000Y281200D02*
X606000D01*
G01X597000Y276800D02*
Y281200D01*
G01X606000Y276800D02*
X597000D01*
G01X600300Y406500D02*
Y415500D01*
G01X604700Y406500D02*
X600300D01*
G01X588800D02*
Y415500D01*
G01X593200Y406500D02*
X588800D01*
G01X593200Y415500D02*
Y406500D01*
G01X600500Y419500D02*
Y428500D01*
G01X604900Y419500D02*
X600500D01*
G01X600300Y415500D02*
X604700D01*
G01X588800D02*
X593200D01*
G01X600500Y428500D02*
X604900D01*
G01X619200Y141000D02*
X614800D01*
G01X619200Y150000D02*
Y141000D01*
G01X614800D02*
Y150000D01*
G01D02*
X619200D01*
G01Y151000D02*
X614800D01*
G01X619200Y160000D02*
Y151000D01*
G01X614800Y160000D02*
X619200D01*
G01X614800Y151000D02*
Y160000D01*
G01X619200Y161000D02*
X614800D01*
G01X619200Y170000D02*
Y161000D01*
G01X614800D02*
Y170000D01*
G01D02*
X619200D01*
G01X613300Y174500D02*
Y183500D01*
G01X617700Y174500D02*
X613300D01*
G01X617700Y183500D02*
Y174500D01*
G01X604702Y197465D02*
X609102D01*
G01X604702Y188465D02*
Y197465D01*
G01X609102Y188465D02*
X604702D01*
G01X609102Y197465D02*
Y188465D01*
G01X604102Y197465D02*
Y188465D01*
G01X618800Y194374D02*
Y203374D01*
G01X623200Y194374D02*
X618800D01*
G01X613300Y183500D02*
X617700D01*
G01X618800Y203374D02*
X623200D01*
G01X606000Y263700D02*
Y259300D01*
G01Y281200D02*
Y276800D01*
G01X612300Y407000D02*
Y416000D01*
G01X616700Y407000D02*
X612300D01*
G01X616700Y416000D02*
Y407000D01*
G01X604700Y415500D02*
Y406500D01*
G01X611800Y419500D02*
Y428500D01*
G01X616200Y419500D02*
X611800D01*
G01X616200Y428500D02*
Y419500D01*
G01X604900Y428500D02*
Y419500D01*
G01X612300Y416000D02*
X616700D01*
G01X611800Y428500D02*
X616200D01*
G01X635500Y94300D02*
Y98700D01*
G01X644500Y94300D02*
X635500D01*
G01Y98700D02*
X644500D01*
G01X635500Y99800D02*
Y104200D01*
G01X644500Y99800D02*
X635500D01*
G01Y104200D02*
X644500D01*
G01X635500Y105800D02*
Y110200D01*
G01X644500Y105800D02*
X635500D01*
G01Y110200D02*
X644500D01*
G01X623200Y203374D02*
Y194374D01*
G01X627700D02*
X623300D01*
G01X627700Y203374D02*
Y194374D01*
G01X623300D02*
Y203374D01*
G01X627800Y194374D02*
Y203374D01*
G01X632200Y194374D02*
X627800D01*
G01X632200Y203374D02*
Y194374D01*
G01X623300Y203374D02*
X627700D01*
G01X627800D02*
X632200D01*
G01X644500Y98700D02*
Y94300D01*
G01Y104200D02*
Y99800D01*
G01Y110200D02*
Y105800D01*
G01X15417Y298450D02*
Y301550D01*
X14458D01*
X14152Y301395D01*
X13960Y301188D01*
X13883Y300775D01*
X13960Y300362D01*
X14190Y300103D01*
X14458Y299948D01*
X15417D01*
G01X14458D02*
X13883Y298450D01*
G01X12393Y299070D02*
X12163Y298708D01*
X11857Y298502D01*
X11512Y298450D01*
X11205Y298502D01*
X10898Y298760D01*
X10707Y299070D01*
X10668Y299380D01*
X10745Y299742D01*
X11013Y300000D01*
X11282Y300103D01*
X11627D01*
G01X11282D02*
X11052Y300258D01*
X10860Y300517D01*
X10783Y300827D01*
X10860Y301137D01*
X11052Y301395D01*
X11397Y301550D01*
X11742Y301498D01*
X12087Y301292D01*
G01X9293Y299070D02*
X9063Y298708D01*
X8757Y298502D01*
X8412Y298450D01*
X8105Y298502D01*
X7798Y298760D01*
X7607Y299070D01*
X7568Y299380D01*
X7645Y299742D01*
X7913Y300000D01*
X8182Y300103D01*
X8527D01*
G01X8182D02*
X7952Y300258D01*
X7760Y300517D01*
X7683Y300827D01*
X7760Y301137D01*
X7952Y301395D01*
X8297Y301550D01*
X8642Y301498D01*
X8987Y301292D01*
G01X5427Y298450D02*
X5350Y299122D01*
X5235Y299690D01*
X5082Y300207D01*
X4890Y300775D01*
X4583Y301550D01*
X6117D01*
G01X15417Y302950D02*
Y306050D01*
X14458D01*
X14152Y305895D01*
X13960Y305688D01*
X13883Y305275D01*
X13960Y304862D01*
X14190Y304603D01*
X14458Y304448D01*
X15417D01*
G01X14458D02*
X13883Y302950D01*
G01X12393Y303570D02*
X12163Y303208D01*
X11857Y303002D01*
X11512Y302950D01*
X11205Y303002D01*
X10898Y303260D01*
X10707Y303570D01*
X10668Y303880D01*
X10745Y304242D01*
X11013Y304500D01*
X11282Y304603D01*
X11627D01*
G01X11282D02*
X11052Y304758D01*
X10860Y305017D01*
X10783Y305327D01*
X10860Y305637D01*
X11052Y305895D01*
X11397Y306050D01*
X11742Y305998D01*
X12087Y305792D01*
G01X9293Y303570D02*
X9063Y303208D01*
X8757Y303002D01*
X8412Y302950D01*
X8105Y303002D01*
X7798Y303260D01*
X7607Y303570D01*
X7568Y303880D01*
X7645Y304242D01*
X7913Y304500D01*
X8182Y304603D01*
X8527D01*
G01X8182D02*
X7952Y304758D01*
X7760Y305017D01*
X7683Y305327D01*
X7760Y305637D01*
X7952Y305895D01*
X8297Y306050D01*
X8642Y305998D01*
X8987Y305792D01*
G01X5350Y302950D02*
X5082Y303002D01*
X4775Y303157D01*
X4583Y303415D01*
X4507Y303777D01*
X4583Y304138D01*
X4813Y304448D01*
X5158Y304603D01*
X5542D01*
X5772Y304707D01*
X5963Y304965D01*
X6040Y305327D01*
X5925Y305688D01*
X5657Y305947D01*
X5350Y306050D01*
X5043Y305947D01*
X4775Y305688D01*
X4660Y305327D01*
X4737Y304965D01*
X4928Y304707D01*
X5158Y304603D01*
X5542D01*
X5887Y304448D01*
X6117Y304138D01*
X6193Y303777D01*
X6117Y303415D01*
X5925Y303157D01*
X5618Y303002D01*
X5350Y302950D01*
G01X15917Y292450D02*
Y295550D01*
X14958D01*
X14652Y295395D01*
X14460Y295188D01*
X14383Y294775D01*
X14460Y294362D01*
X14690Y294103D01*
X14958Y293948D01*
X15917D01*
G01X14958D02*
X14383Y292450D01*
G01X12893Y293070D02*
X12663Y292708D01*
X12357Y292502D01*
X12012Y292450D01*
X11705Y292502D01*
X11398Y292760D01*
X11207Y293070D01*
X11168Y293380D01*
X11245Y293742D01*
X11513Y294000D01*
X11782Y294103D01*
X12127D01*
G01X11782D02*
X11552Y294258D01*
X11360Y294517D01*
X11283Y294827D01*
X11360Y295137D01*
X11552Y295395D01*
X11897Y295550D01*
X12242Y295498D01*
X12587Y295292D01*
G01X9793Y293070D02*
X9563Y292708D01*
X9257Y292502D01*
X8912Y292450D01*
X8605Y292502D01*
X8298Y292760D01*
X8107Y293070D01*
X8068Y293380D01*
X8145Y293742D01*
X8413Y294000D01*
X8682Y294103D01*
X9027D01*
G01X8682D02*
X8452Y294258D01*
X8260Y294517D01*
X8183Y294827D01*
X8260Y295137D01*
X8452Y295395D01*
X8797Y295550D01*
X9142Y295498D01*
X9487Y295292D01*
G01X6693Y292915D02*
X6463Y292657D01*
X6195Y292502D01*
X5850Y292450D01*
X5505Y292553D01*
X5237Y292760D01*
X5045Y293122D01*
X5007Y293535D01*
X5083Y293948D01*
X5275Y294207D01*
X5543Y294413D01*
X5812Y294465D01*
X6080Y294413D01*
X6425Y294207D01*
X6310Y295550D01*
X5275D01*
G01X15917Y288450D02*
Y291550D01*
X14958D01*
X14652Y291395D01*
X14460Y291188D01*
X14383Y290775D01*
X14460Y290362D01*
X14690Y290103D01*
X14958Y289948D01*
X15917D01*
G01X14958D02*
X14383Y288450D01*
G01X12893Y289070D02*
X12663Y288708D01*
X12357Y288502D01*
X12012Y288450D01*
X11705Y288502D01*
X11398Y288760D01*
X11207Y289070D01*
X11168Y289380D01*
X11245Y289742D01*
X11513Y290000D01*
X11782Y290103D01*
X12127D01*
G01X11782D02*
X11552Y290258D01*
X11360Y290517D01*
X11283Y290827D01*
X11360Y291137D01*
X11552Y291395D01*
X11897Y291550D01*
X12242Y291498D01*
X12587Y291292D01*
G01X9793Y289070D02*
X9563Y288708D01*
X9257Y288502D01*
X8912Y288450D01*
X8605Y288502D01*
X8298Y288760D01*
X8107Y289070D01*
X8068Y289380D01*
X8145Y289742D01*
X8413Y290000D01*
X8682Y290103D01*
X9027D01*
G01X8682D02*
X8452Y290258D01*
X8260Y290517D01*
X8183Y290827D01*
X8260Y291137D01*
X8452Y291395D01*
X8797Y291550D01*
X9142Y291498D01*
X9487Y291292D01*
G01X6578Y289742D02*
X6310Y290103D01*
X6080Y290310D01*
X5773Y290413D01*
X5505Y290310D01*
X5313Y290103D01*
X5160Y289793D01*
X5122Y289432D01*
X5160Y289122D01*
X5313Y288812D01*
X5543Y288553D01*
X5812Y288450D01*
X6118Y288553D01*
X6387Y288863D01*
X6540Y289328D01*
X6578Y289845D01*
X6502Y290517D01*
X6387Y290878D01*
X6195Y291240D01*
X5927Y291498D01*
X5658Y291550D01*
X5390Y291447D01*
X5198Y291188D01*
G01X12257Y309292D02*
X12487Y309447D01*
X12755Y309550D01*
X13062D01*
X13407Y309395D01*
X13675Y309137D01*
X13867Y308827D01*
X14020Y308310D01*
X14058Y307845D01*
X13982Y307380D01*
X13867Y307070D01*
X13637Y306760D01*
X13368Y306553D01*
X13100Y306450D01*
X12832D01*
X12563Y306553D01*
X12333Y306708D01*
X12142Y306915D01*
G01X10843Y307070D02*
X10613Y306708D01*
X10307Y306502D01*
X9962Y306450D01*
X9655Y306502D01*
X9348Y306760D01*
X9157Y307070D01*
X9118Y307380D01*
X9195Y307742D01*
X9463Y308000D01*
X9732Y308103D01*
X10077D01*
G01X9732D02*
X9502Y308258D01*
X9310Y308517D01*
X9233Y308827D01*
X9310Y309137D01*
X9502Y309395D01*
X9847Y309550D01*
X10192Y309498D01*
X10537Y309292D01*
G01X7552Y306812D02*
X7283Y306553D01*
X6977Y306450D01*
X6670Y306553D01*
X6402Y306863D01*
X6210Y307328D01*
X6133Y307793D01*
Y308362D01*
X6210Y308827D01*
X6402Y309240D01*
X6632Y309447D01*
X6900Y309550D01*
X7207Y309447D01*
X7437Y309240D01*
X7590Y308930D01*
X7667Y308517D01*
X7590Y308155D01*
X7398Y307793D01*
X7168Y307587D01*
X6900Y307535D01*
X6593Y307638D01*
X6363Y307897D01*
X6133Y308362D01*
G01X42450Y278083D02*
X45550D01*
Y279042D01*
X45395Y279348D01*
X45188Y279540D01*
X44775Y279617D01*
X44362Y279540D01*
X44103Y279310D01*
X43948Y279042D01*
Y278083D01*
G01Y279042D02*
X42450Y279617D01*
G01X43070Y281107D02*
X42708Y281337D01*
X42502Y281643D01*
X42450Y281988D01*
X42502Y282295D01*
X42760Y282602D01*
X43070Y282793D01*
X43380Y282832D01*
X43742Y282755D01*
X44000Y282487D01*
X44103Y282218D01*
Y281873D01*
G01Y282218D02*
X44258Y282448D01*
X44517Y282640D01*
X44827Y282717D01*
X45137Y282640D01*
X45395Y282448D01*
X45550Y282103D01*
X45498Y281758D01*
X45292Y281413D01*
G01X43070Y284207D02*
X42708Y284437D01*
X42502Y284743D01*
X42450Y285088D01*
X42502Y285395D01*
X42760Y285702D01*
X43070Y285893D01*
X43380Y285932D01*
X43742Y285855D01*
X44000Y285587D01*
X44103Y285318D01*
Y284973D01*
G01Y285318D02*
X44258Y285548D01*
X44517Y285740D01*
X44827Y285817D01*
X45137Y285740D01*
X45395Y285548D01*
X45550Y285203D01*
X45498Y284858D01*
X45292Y284513D01*
G01X43070Y287307D02*
X42708Y287537D01*
X42502Y287843D01*
X42450Y288188D01*
X42502Y288495D01*
X42760Y288802D01*
X43070Y288993D01*
X43380Y289032D01*
X43742Y288955D01*
X44000Y288687D01*
X44103Y288418D01*
Y288073D01*
G01Y288418D02*
X44258Y288648D01*
X44517Y288840D01*
X44827Y288917D01*
X45137Y288840D01*
X45395Y288648D01*
X45550Y288303D01*
X45498Y287958D01*
X45292Y287613D01*
G01X38450Y278083D02*
X41550D01*
Y279042D01*
X41395Y279348D01*
X41188Y279540D01*
X40775Y279617D01*
X40362Y279540D01*
X40103Y279310D01*
X39948Y279042D01*
Y278083D01*
G01Y279042D02*
X38450Y279617D01*
G01X39070Y281107D02*
X38708Y281337D01*
X38502Y281643D01*
X38450Y281988D01*
X38502Y282295D01*
X38760Y282602D01*
X39070Y282793D01*
X39380Y282832D01*
X39742Y282755D01*
X40000Y282487D01*
X40103Y282218D01*
Y281873D01*
G01Y282218D02*
X40258Y282448D01*
X40517Y282640D01*
X40827Y282717D01*
X41137Y282640D01*
X41395Y282448D01*
X41550Y282103D01*
X41498Y281758D01*
X41292Y281413D01*
G01X39070Y284207D02*
X38708Y284437D01*
X38502Y284743D01*
X38450Y285088D01*
X38502Y285395D01*
X38760Y285702D01*
X39070Y285893D01*
X39380Y285932D01*
X39742Y285855D01*
X40000Y285587D01*
X40103Y285318D01*
Y284973D01*
G01Y285318D02*
X40258Y285548D01*
X40517Y285740D01*
X40827Y285817D01*
X41137Y285740D01*
X41395Y285548D01*
X41550Y285203D01*
X41498Y284858D01*
X41292Y284513D01*
G01X38450Y288610D02*
X41550D01*
X39328Y287192D01*
Y289108D01*
G01X32343Y293915D02*
X32113Y293657D01*
X31845Y293502D01*
X31500Y293450D01*
X31155Y293553D01*
X30887Y293760D01*
X30695Y294122D01*
X30657Y294535D01*
X30733Y294948D01*
X30925Y295207D01*
X31193Y295413D01*
X31462Y295465D01*
X31730Y295413D01*
X32075Y295207D01*
X31960Y296550D01*
X30925D01*
G01X31000Y302950D02*
X30732Y303002D01*
X30425Y303157D01*
X30233Y303415D01*
X30157Y303777D01*
X30233Y304138D01*
X30463Y304448D01*
X30808Y304603D01*
X31192D01*
X31422Y304707D01*
X31613Y304965D01*
X31690Y305327D01*
X31575Y305688D01*
X31307Y305947D01*
X31000Y306050D01*
X30693Y305947D01*
X30425Y305688D01*
X30310Y305327D01*
X30387Y304965D01*
X30578Y304707D01*
X30808Y304603D01*
X31192D01*
X31537Y304448D01*
X31767Y304138D01*
X31843Y303777D01*
X31767Y303415D01*
X31575Y303157D01*
X31268Y303002D01*
X31000Y302950D01*
G01X68757Y58292D02*
X68987Y58447D01*
X69255Y58550D01*
X69562D01*
X69907Y58395D01*
X70175Y58137D01*
X70367Y57827D01*
X70520Y57310D01*
X70558Y56845D01*
X70482Y56380D01*
X70367Y56070D01*
X70137Y55760D01*
X69868Y55553D01*
X69600Y55450D01*
X69332D01*
X69063Y55553D01*
X68833Y55708D01*
X68642Y55915D01*
G01X66500Y55450D02*
X66232Y55502D01*
X65925Y55657D01*
X65733Y55915D01*
X65657Y56277D01*
X65733Y56638D01*
X65963Y56948D01*
X66308Y57103D01*
X66692D01*
X66922Y57207D01*
X67113Y57465D01*
X67190Y57827D01*
X67075Y58188D01*
X66807Y58447D01*
X66500Y58550D01*
X66193Y58447D01*
X65925Y58188D01*
X65810Y57827D01*
X65887Y57465D01*
X66078Y57207D01*
X66308Y57103D01*
X66692D01*
X67037Y56948D01*
X67267Y56638D01*
X67343Y56277D01*
X67267Y55915D01*
X67075Y55657D01*
X66768Y55502D01*
X66500Y55450D01*
G01X64128Y58033D02*
X63898Y58343D01*
X63630Y58498D01*
X63323Y58550D01*
X62940Y58447D01*
X62672Y58188D01*
X62595Y57878D01*
X62633Y57568D01*
X62787Y57310D01*
X63553Y56793D01*
X63898Y56432D01*
X64128Y55915D01*
X64205Y55450D01*
X62595D01*
G01X56250Y72667D02*
X58750D01*
Y73333D01*
X58625Y73547D01*
X58458Y73680D01*
X58125Y73733D01*
X57792Y73680D01*
X57583Y73520D01*
X57458Y73333D01*
Y72667D01*
G01Y73333D02*
X56250Y73733D01*
G01X56750Y74813D02*
X56458Y74973D01*
X56292Y75187D01*
X56250Y75427D01*
X56292Y75640D01*
X56500Y75853D01*
X56750Y75987D01*
X57000Y76013D01*
X57292Y75960D01*
X57500Y75773D01*
X57583Y75587D01*
Y75347D01*
G01Y75587D02*
X57708Y75747D01*
X57917Y75880D01*
X58167Y75933D01*
X58417Y75880D01*
X58625Y75747D01*
X58750Y75507D01*
X58708Y75267D01*
X58542Y75027D01*
G01X56250Y77547D02*
X56792Y77600D01*
X57250Y77680D01*
X57667Y77787D01*
X58125Y77920D01*
X58750Y78133D01*
Y77067D01*
G01X56542Y79347D02*
X56333Y79533D01*
X56250Y79747D01*
X56333Y79960D01*
X56583Y80147D01*
X56958Y80280D01*
X57333Y80333D01*
X57792D01*
X58167Y80280D01*
X58500Y80147D01*
X58667Y79987D01*
X58750Y79800D01*
X58667Y79587D01*
X58500Y79427D01*
X58250Y79320D01*
X57917Y79267D01*
X57625Y79320D01*
X57333Y79453D01*
X57167Y79613D01*
X57125Y79800D01*
X57208Y80013D01*
X57417Y80173D01*
X57792Y80333D01*
G01X52750Y72667D02*
X55250D01*
Y73333D01*
X55125Y73547D01*
X54958Y73680D01*
X54625Y73733D01*
X54292Y73680D01*
X54083Y73520D01*
X53958Y73333D01*
Y72667D01*
G01Y73333D02*
X52750Y73733D01*
G01Y75400D02*
X55250D01*
X54750Y75080D01*
G01X52750D02*
Y75720D01*
G01X54833Y77093D02*
X55083Y77253D01*
X55208Y77440D01*
X55250Y77653D01*
X55167Y77920D01*
X54958Y78107D01*
X54708Y78160D01*
X54458Y78133D01*
X54250Y78027D01*
X53833Y77493D01*
X53542Y77253D01*
X53125Y77093D01*
X52750Y77040D01*
Y78160D01*
G01X53250Y79213D02*
X52958Y79373D01*
X52792Y79587D01*
X52750Y79827D01*
X52792Y80040D01*
X53000Y80253D01*
X53250Y80387D01*
X53500Y80413D01*
X53792Y80360D01*
X54000Y80173D01*
X54083Y79987D01*
Y79747D01*
G01Y79987D02*
X54208Y80147D01*
X54417Y80280D01*
X54667Y80333D01*
X54917Y80280D01*
X55125Y80147D01*
X55250Y79907D01*
X55208Y79667D01*
X55042Y79427D01*
G01X56250Y86667D02*
X58750D01*
Y87333D01*
X58625Y87547D01*
X58458Y87680D01*
X58125Y87733D01*
X57792Y87680D01*
X57583Y87520D01*
X57458Y87333D01*
Y86667D01*
G01Y87333D02*
X56250Y87733D01*
G01Y89720D02*
X58750D01*
X56958Y88733D01*
Y90067D01*
G01X56542Y91147D02*
X56333Y91333D01*
X56250Y91547D01*
X56333Y91760D01*
X56583Y91947D01*
X56958Y92080D01*
X57333Y92133D01*
X57792D01*
X58167Y92080D01*
X58500Y91947D01*
X58667Y91787D01*
X58750Y91600D01*
X58667Y91387D01*
X58500Y91227D01*
X58250Y91120D01*
X57917Y91067D01*
X57625Y91120D01*
X57333Y91253D01*
X57167Y91413D01*
X57125Y91600D01*
X57208Y91813D01*
X57417Y91973D01*
X57792Y92133D01*
G01X56750Y93213D02*
X56458Y93373D01*
X56292Y93587D01*
X56250Y93827D01*
X56292Y94040D01*
X56500Y94253D01*
X56750Y94387D01*
X57000Y94413D01*
X57292Y94360D01*
X57500Y94173D01*
X57583Y93987D01*
Y93747D01*
G01Y93987D02*
X57708Y94147D01*
X57917Y94280D01*
X58167Y94333D01*
X58417Y94280D01*
X58625Y94147D01*
X58750Y93907D01*
X58708Y93667D01*
X58542Y93427D01*
G01X73417Y142950D02*
Y146050D01*
X72458D01*
X72152Y145895D01*
X71960Y145688D01*
X71883Y145275D01*
X71960Y144862D01*
X72190Y144603D01*
X72458Y144448D01*
X73417D01*
G01X72458D02*
X71883Y142950D01*
G01X69550D02*
Y146050D01*
X70010Y145430D01*
G01Y142950D02*
X69090D01*
G01X65990D02*
Y146050D01*
X67408Y143828D01*
X65492D01*
G01X64193Y143415D02*
X63963Y143157D01*
X63695Y143002D01*
X63350Y142950D01*
X63005Y143053D01*
X62737Y143260D01*
X62545Y143622D01*
X62507Y144035D01*
X62583Y144448D01*
X62775Y144707D01*
X63043Y144913D01*
X63312Y144965D01*
X63580Y144913D01*
X63925Y144707D01*
X63810Y146050D01*
X62775D01*
G01X58450Y135083D02*
X61550D01*
Y136042D01*
X61395Y136348D01*
X61188Y136540D01*
X60775Y136617D01*
X60362Y136540D01*
X60103Y136310D01*
X59948Y136042D01*
Y135083D01*
G01Y136042D02*
X58450Y136617D01*
G01Y139410D02*
X61550D01*
X59328Y137992D01*
Y139908D01*
G01X58812Y141398D02*
X58553Y141667D01*
X58450Y141973D01*
X58553Y142280D01*
X58863Y142548D01*
X59328Y142740D01*
X59793Y142817D01*
X60362D01*
X60827Y142740D01*
X61240Y142548D01*
X61447Y142318D01*
X61550Y142050D01*
X61447Y141743D01*
X61240Y141513D01*
X60930Y141360D01*
X60517Y141283D01*
X60155Y141360D01*
X59793Y141552D01*
X59587Y141782D01*
X59535Y142050D01*
X59638Y142357D01*
X59897Y142587D01*
X60362Y142817D01*
G01X61033Y144422D02*
X61343Y144652D01*
X61498Y144920D01*
X61550Y145227D01*
X61447Y145610D01*
X61188Y145878D01*
X60878Y145955D01*
X60568Y145917D01*
X60310Y145763D01*
X59793Y144997D01*
X59432Y144652D01*
X58915Y144422D01*
X58450Y144345D01*
Y145955D01*
G01X73417Y162950D02*
Y166050D01*
X72458D01*
X72152Y165895D01*
X71960Y165688D01*
X71883Y165275D01*
X71960Y164862D01*
X72190Y164603D01*
X72458Y164448D01*
X73417D01*
G01X72458D02*
X71883Y162950D01*
G01X69550D02*
Y166050D01*
X70010Y165430D01*
G01Y162950D02*
X69090D01*
G01X65990D02*
Y166050D01*
X67408Y163828D01*
X65492D01*
G01X62890Y162950D02*
Y166050D01*
X64308Y163828D01*
X62392D01*
G01X55950Y201583D02*
X59050D01*
Y202542D01*
X58895Y202848D01*
X58688Y203040D01*
X58275Y203117D01*
X57862Y203040D01*
X57603Y202810D01*
X57448Y202542D01*
Y201583D01*
G01Y202542D02*
X55950Y203117D01*
G01Y205910D02*
X59050D01*
X56828Y204492D01*
Y206408D01*
G01X56312Y207898D02*
X56053Y208167D01*
X55950Y208473D01*
X56053Y208780D01*
X56363Y209048D01*
X56828Y209240D01*
X57293Y209317D01*
X57862D01*
X58327Y209240D01*
X58740Y209048D01*
X58947Y208818D01*
X59050Y208550D01*
X58947Y208243D01*
X58740Y208013D01*
X58430Y207860D01*
X58017Y207783D01*
X57655Y207860D01*
X57293Y208052D01*
X57087Y208282D01*
X57035Y208550D01*
X57138Y208857D01*
X57397Y209087D01*
X57862Y209317D01*
G01X56415Y210807D02*
X56157Y211037D01*
X56002Y211305D01*
X55950Y211650D01*
X56053Y211995D01*
X56260Y212263D01*
X56622Y212455D01*
X57035Y212493D01*
X57448Y212417D01*
X57707Y212225D01*
X57913Y211957D01*
X57965Y211688D01*
X57913Y211420D01*
X57707Y211075D01*
X59050Y211190D01*
Y212225D01*
G01X59450Y235383D02*
X62550D01*
Y236342D01*
X62395Y236648D01*
X62188Y236840D01*
X61775Y236917D01*
X61362Y236840D01*
X61103Y236610D01*
X60948Y236342D01*
Y235383D01*
G01Y236342D02*
X59450Y236917D01*
G01X60070Y238407D02*
X59708Y238637D01*
X59502Y238943D01*
X59450Y239288D01*
X59502Y239595D01*
X59760Y239902D01*
X60070Y240093D01*
X60380Y240132D01*
X60742Y240055D01*
X61000Y239787D01*
X61103Y239518D01*
Y239173D01*
G01Y239518D02*
X61258Y239748D01*
X61517Y239940D01*
X61827Y240017D01*
X62137Y239940D01*
X62395Y239748D01*
X62550Y239403D01*
X62498Y239058D01*
X62292Y238713D01*
G01X59450Y242350D02*
X62550D01*
X61930Y241890D01*
G01X59450D02*
Y242810D01*
G01X59915Y244607D02*
X59657Y244837D01*
X59502Y245105D01*
X59450Y245450D01*
X59553Y245795D01*
X59760Y246063D01*
X60122Y246255D01*
X60535Y246293D01*
X60948Y246217D01*
X61207Y246025D01*
X61413Y245757D01*
X61465Y245488D01*
X61413Y245220D01*
X61207Y244875D01*
X62550Y244990D01*
Y246025D01*
G01X63450Y235583D02*
X66550D01*
Y236542D01*
X66395Y236848D01*
X66188Y237040D01*
X65775Y237117D01*
X65362Y237040D01*
X65103Y236810D01*
X64948Y236542D01*
Y235583D01*
G01Y236542D02*
X63450Y237117D01*
G01X64070Y238607D02*
X63708Y238837D01*
X63502Y239143D01*
X63450Y239488D01*
X63502Y239795D01*
X63760Y240102D01*
X64070Y240293D01*
X64380Y240332D01*
X64742Y240255D01*
X65000Y239987D01*
X65103Y239718D01*
Y239373D01*
G01Y239718D02*
X65258Y239948D01*
X65517Y240140D01*
X65827Y240217D01*
X66137Y240140D01*
X66395Y239948D01*
X66550Y239603D01*
X66498Y239258D01*
X66292Y238913D01*
G01X63450Y242550D02*
X66550D01*
X65930Y242090D01*
G01X63450D02*
Y243010D01*
G01X64742Y244922D02*
X65103Y245190D01*
X65310Y245420D01*
X65413Y245727D01*
X65310Y245995D01*
X65103Y246187D01*
X64793Y246340D01*
X64432Y246378D01*
X64122Y246340D01*
X63812Y246187D01*
X63553Y245957D01*
X63450Y245688D01*
X63553Y245382D01*
X63863Y245113D01*
X64328Y244960D01*
X64845Y244922D01*
X65517Y244998D01*
X65878Y245113D01*
X66240Y245305D01*
X66498Y245573D01*
X66550Y245842D01*
X66447Y246110D01*
X66188Y246302D01*
G01X55450Y235383D02*
X58550D01*
Y236342D01*
X58395Y236648D01*
X58188Y236840D01*
X57775Y236917D01*
X57362Y236840D01*
X57103Y236610D01*
X56948Y236342D01*
Y235383D01*
G01Y236342D02*
X55450Y236917D01*
G01X58033Y238522D02*
X58343Y238752D01*
X58498Y239020D01*
X58550Y239327D01*
X58447Y239710D01*
X58188Y239978D01*
X57878Y240055D01*
X57568Y240017D01*
X57310Y239863D01*
X56793Y239097D01*
X56432Y238752D01*
X55915Y238522D01*
X55450Y238445D01*
Y240055D01*
G01Y242350D02*
X55502Y242618D01*
X55657Y242925D01*
X55915Y243117D01*
X56277Y243193D01*
X56638Y243117D01*
X56948Y242887D01*
X57103Y242542D01*
Y242158D01*
X57207Y241928D01*
X57465Y241737D01*
X57827Y241660D01*
X58188Y241775D01*
X58447Y242043D01*
X58550Y242350D01*
X58447Y242657D01*
X58188Y242925D01*
X57827Y243040D01*
X57465Y242963D01*
X57207Y242772D01*
X57103Y242542D01*
Y242158D01*
X56948Y241813D01*
X56638Y241583D01*
X56277Y241507D01*
X55915Y241583D01*
X55657Y241775D01*
X55502Y242082D01*
X55450Y242350D01*
G01X58033Y244722D02*
X58343Y244952D01*
X58498Y245220D01*
X58550Y245527D01*
X58447Y245910D01*
X58188Y246178D01*
X57878Y246255D01*
X57568Y246217D01*
X57310Y246063D01*
X56793Y245297D01*
X56432Y244952D01*
X55915Y244722D01*
X55450Y244645D01*
Y246255D01*
G01X56450Y255083D02*
X59550D01*
Y256042D01*
X59395Y256348D01*
X59188Y256540D01*
X58775Y256617D01*
X58362Y256540D01*
X58103Y256310D01*
X57948Y256042D01*
Y255083D01*
G01Y256042D02*
X56450Y256617D01*
G01Y259410D02*
X59550D01*
X57328Y257992D01*
Y259908D01*
G01X56812Y261398D02*
X56553Y261667D01*
X56450Y261973D01*
X56553Y262280D01*
X56863Y262548D01*
X57328Y262740D01*
X57793Y262817D01*
X58362D01*
X58827Y262740D01*
X59240Y262548D01*
X59447Y262318D01*
X59550Y262050D01*
X59447Y261743D01*
X59240Y261513D01*
X58930Y261360D01*
X58517Y261283D01*
X58155Y261360D01*
X57793Y261552D01*
X57587Y261782D01*
X57535Y262050D01*
X57638Y262357D01*
X57897Y262587D01*
X58362Y262817D01*
G01X56450Y265610D02*
X59550D01*
X57328Y264192D01*
Y266108D01*
G01X53393Y289550D02*
Y287328D01*
X53240Y286863D01*
X52933Y286553D01*
X52550Y286450D01*
X52167Y286553D01*
X51860Y286863D01*
X51707Y287328D01*
Y289550D01*
G01X49450Y286450D02*
X49182Y286502D01*
X48875Y286657D01*
X48683Y286915D01*
X48607Y287277D01*
X48683Y287638D01*
X48913Y287948D01*
X49258Y288103D01*
X49642D01*
X49872Y288207D01*
X50063Y288465D01*
X50140Y288827D01*
X50025Y289188D01*
X49757Y289447D01*
X49450Y289550D01*
X49143Y289447D01*
X48875Y289188D01*
X48760Y288827D01*
X48837Y288465D01*
X49028Y288207D01*
X49258Y288103D01*
X49642D01*
X49987Y287948D01*
X50217Y287638D01*
X50293Y287277D01*
X50217Y286915D01*
X50025Y286657D01*
X49718Y286502D01*
X49450Y286450D01*
G01X60540Y294450D02*
Y297550D01*
X61958Y295328D01*
X60042D01*
G01X73950Y70183D02*
X77050D01*
Y71142D01*
X76895Y71448D01*
X76688Y71640D01*
X76275Y71717D01*
X75862Y71640D01*
X75603Y71410D01*
X75448Y71142D01*
Y70183D01*
G01Y71142D02*
X73950Y71717D01*
G01X76533Y73322D02*
X76843Y73552D01*
X76998Y73820D01*
X77050Y74127D01*
X76947Y74510D01*
X76688Y74778D01*
X76378Y74855D01*
X76068Y74817D01*
X75810Y74663D01*
X75293Y73897D01*
X74932Y73552D01*
X74415Y73322D01*
X73950Y73245D01*
Y74855D01*
G01X66450Y79633D02*
X69550D01*
Y80592D01*
X69395Y80898D01*
X69188Y81090D01*
X68775Y81167D01*
X68362Y81090D01*
X68103Y80860D01*
X67948Y80592D01*
Y79633D01*
G01Y80592D02*
X66450Y81167D01*
G01Y83960D02*
X69550D01*
X67328Y82542D01*
Y84458D01*
G01X66915Y85757D02*
X66657Y85987D01*
X66502Y86255D01*
X66450Y86600D01*
X66553Y86945D01*
X66760Y87213D01*
X67122Y87405D01*
X67535Y87443D01*
X67948Y87367D01*
X68207Y87175D01*
X68413Y86907D01*
X68465Y86638D01*
X68413Y86370D01*
X68207Y86025D01*
X69550Y86140D01*
Y87175D01*
G01X63950Y93083D02*
X67050D01*
Y94042D01*
X66895Y94348D01*
X66688Y94540D01*
X66275Y94617D01*
X65862Y94540D01*
X65603Y94310D01*
X65448Y94042D01*
Y93083D01*
G01Y94042D02*
X63950Y94617D01*
G01Y96950D02*
X67050D01*
X66430Y96490D01*
G01X63950D02*
Y97410D01*
G01X65242Y99322D02*
X65603Y99590D01*
X65810Y99820D01*
X65913Y100127D01*
X65810Y100395D01*
X65603Y100587D01*
X65293Y100740D01*
X64932Y100778D01*
X64622Y100740D01*
X64312Y100587D01*
X64053Y100357D01*
X63950Y100088D01*
X64053Y99782D01*
X64363Y99513D01*
X64828Y99360D01*
X65345Y99322D01*
X66017Y99398D01*
X66378Y99513D01*
X66740Y99705D01*
X66998Y99973D01*
X67050Y100242D01*
X66947Y100510D01*
X66688Y100702D01*
G01X64570Y102307D02*
X64208Y102537D01*
X64002Y102843D01*
X63950Y103188D01*
X64002Y103495D01*
X64260Y103802D01*
X64570Y103993D01*
X64880Y104032D01*
X65242Y103955D01*
X65500Y103687D01*
X65603Y103418D01*
Y103073D01*
G01Y103418D02*
X65758Y103648D01*
X66017Y103840D01*
X66327Y103917D01*
X66637Y103840D01*
X66895Y103648D01*
X67050Y103303D01*
X66998Y102958D01*
X66792Y102613D01*
G01X68950Y100583D02*
X72050D01*
Y101542D01*
X71895Y101848D01*
X71688Y102040D01*
X71275Y102117D01*
X70862Y102040D01*
X70603Y101810D01*
X70448Y101542D01*
Y100583D01*
G01Y101542D02*
X68950Y102117D01*
G01Y104450D02*
X72050D01*
X71430Y103990D01*
G01X68950D02*
Y104910D01*
G01X70242Y106822D02*
X70603Y107090D01*
X70810Y107320D01*
X70913Y107627D01*
X70810Y107895D01*
X70603Y108087D01*
X70293Y108240D01*
X69932Y108278D01*
X69622Y108240D01*
X69312Y108087D01*
X69053Y107857D01*
X68950Y107588D01*
X69053Y107282D01*
X69363Y107013D01*
X69828Y106860D01*
X70345Y106822D01*
X71017Y106898D01*
X71378Y107013D01*
X71740Y107205D01*
X71998Y107473D01*
X72050Y107742D01*
X71947Y108010D01*
X71688Y108202D01*
G01X71533Y109922D02*
X71843Y110152D01*
X71998Y110420D01*
X72050Y110727D01*
X71947Y111110D01*
X71688Y111378D01*
X71378Y111455D01*
X71068Y111417D01*
X70810Y111263D01*
X70293Y110497D01*
X69932Y110152D01*
X69415Y109922D01*
X68950Y109845D01*
Y111455D01*
G01X78450Y103083D02*
X81550D01*
Y104042D01*
X81395Y104348D01*
X81188Y104540D01*
X80775Y104617D01*
X80362Y104540D01*
X80103Y104310D01*
X79948Y104042D01*
Y103083D01*
G01Y104042D02*
X78450Y104617D01*
G01Y106950D02*
X81550D01*
X80930Y106490D01*
G01X78450D02*
Y107410D01*
G01X79742Y109322D02*
X80103Y109590D01*
X80310Y109820D01*
X80413Y110127D01*
X80310Y110395D01*
X80103Y110587D01*
X79793Y110740D01*
X79432Y110778D01*
X79122Y110740D01*
X78812Y110587D01*
X78553Y110357D01*
X78450Y110088D01*
X78553Y109782D01*
X78863Y109513D01*
X79328Y109360D01*
X79845Y109322D01*
X80517Y109398D01*
X80878Y109513D01*
X81240Y109705D01*
X81498Y109973D01*
X81550Y110242D01*
X81447Y110510D01*
X81188Y110702D01*
G01X81550Y113150D02*
X81447Y112843D01*
X81188Y112613D01*
X80878Y112460D01*
X80465Y112345D01*
X80000Y112307D01*
X79535Y112345D01*
X79122Y112460D01*
X78812Y112613D01*
X78553Y112843D01*
X78450Y113150D01*
X78553Y113457D01*
X78812Y113687D01*
X79122Y113840D01*
X79535Y113955D01*
X80000Y113993D01*
X80465Y113955D01*
X80878Y113840D01*
X81188Y113687D01*
X81447Y113457D01*
X81550Y113150D01*
G01X86917Y143450D02*
Y146550D01*
X85958D01*
X85652Y146395D01*
X85460Y146188D01*
X85383Y145775D01*
X85460Y145362D01*
X85690Y145103D01*
X85958Y144948D01*
X86917D01*
G01X85958D02*
X85383Y143450D01*
G01X83050D02*
Y146550D01*
X83510Y145930D01*
G01Y143450D02*
X82590D01*
G01X79490D02*
Y146550D01*
X80908Y144328D01*
X78992D01*
G01X76927Y143450D02*
X76850Y144122D01*
X76735Y144690D01*
X76582Y145207D01*
X76390Y145775D01*
X76083Y146550D01*
X77617D01*
G01X85267Y138850D02*
Y141950D01*
X84308D01*
X84002Y141795D01*
X83810Y141588D01*
X83733Y141175D01*
X83810Y140762D01*
X84040Y140503D01*
X84308Y140348D01*
X85267D01*
G01X84308D02*
X83733Y138850D01*
G01X82128Y141433D02*
X81898Y141743D01*
X81630Y141898D01*
X81323Y141950D01*
X80940Y141847D01*
X80672Y141588D01*
X80595Y141278D01*
X80633Y140968D01*
X80787Y140710D01*
X81553Y140193D01*
X81898Y139832D01*
X82128Y139315D01*
X82205Y138850D01*
X80595D01*
G01X79028Y140142D02*
X78760Y140503D01*
X78530Y140710D01*
X78223Y140813D01*
X77955Y140710D01*
X77763Y140503D01*
X77610Y140193D01*
X77572Y139832D01*
X77610Y139522D01*
X77763Y139212D01*
X77993Y138953D01*
X78262Y138850D01*
X78568Y138953D01*
X78837Y139263D01*
X78990Y139728D01*
X79028Y140245D01*
X78952Y140917D01*
X78837Y141278D01*
X78645Y141640D01*
X78377Y141898D01*
X78108Y141950D01*
X77840Y141847D01*
X77648Y141588D01*
G01X86867Y130950D02*
Y134050D01*
X85908D01*
X85602Y133895D01*
X85410Y133688D01*
X85333Y133275D01*
X85410Y132862D01*
X85640Y132603D01*
X85908Y132448D01*
X86867D01*
G01X85908D02*
X85333Y130950D01*
G01X83728Y133533D02*
X83498Y133843D01*
X83230Y133998D01*
X82923Y134050D01*
X82540Y133947D01*
X82272Y133688D01*
X82195Y133378D01*
X82233Y133068D01*
X82387Y132810D01*
X83153Y132293D01*
X83498Y131932D01*
X83728Y131415D01*
X83805Y130950D01*
X82195D01*
G01X79977D02*
X79900Y131622D01*
X79785Y132190D01*
X79632Y132707D01*
X79440Y133275D01*
X79133Y134050D01*
X80667D01*
G01X73367Y138950D02*
Y142050D01*
X72408D01*
X72102Y141895D01*
X71910Y141688D01*
X71833Y141275D01*
X71910Y140862D01*
X72140Y140603D01*
X72408Y140448D01*
X73367D01*
G01X72408D02*
X71833Y138950D01*
G01X70343Y139415D02*
X70113Y139157D01*
X69845Y139002D01*
X69500Y138950D01*
X69155Y139053D01*
X68887Y139260D01*
X68695Y139622D01*
X68657Y140035D01*
X68733Y140448D01*
X68925Y140707D01*
X69193Y140913D01*
X69462Y140965D01*
X69730Y140913D01*
X70075Y140707D01*
X69960Y142050D01*
X68925D01*
G01X67052Y139312D02*
X66783Y139053D01*
X66477Y138950D01*
X66170Y139053D01*
X65902Y139363D01*
X65710Y139828D01*
X65633Y140293D01*
Y140862D01*
X65710Y141327D01*
X65902Y141740D01*
X66132Y141947D01*
X66400Y142050D01*
X66707Y141947D01*
X66937Y141740D01*
X67090Y141430D01*
X67167Y141017D01*
X67090Y140655D01*
X66898Y140293D01*
X66668Y140087D01*
X66400Y140035D01*
X66093Y140138D01*
X65863Y140397D01*
X65633Y140862D01*
G01X86917Y134950D02*
Y138050D01*
X85958D01*
X85652Y137895D01*
X85460Y137688D01*
X85383Y137275D01*
X85460Y136862D01*
X85690Y136603D01*
X85958Y136448D01*
X86917D01*
G01X85958D02*
X85383Y134950D01*
G01X83050D02*
Y138050D01*
X83510Y137430D01*
G01Y134950D02*
X82590D01*
G01X79490D02*
Y138050D01*
X80908Y135828D01*
X78992D01*
G01X76850Y134950D02*
X76582Y135002D01*
X76275Y135157D01*
X76083Y135415D01*
X76007Y135777D01*
X76083Y136138D01*
X76313Y136448D01*
X76658Y136603D01*
X77042D01*
X77272Y136707D01*
X77463Y136965D01*
X77540Y137327D01*
X77425Y137688D01*
X77157Y137947D01*
X76850Y138050D01*
X76543Y137947D01*
X76275Y137688D01*
X76160Y137327D01*
X76237Y136965D01*
X76428Y136707D01*
X76658Y136603D01*
X77042D01*
X77387Y136448D01*
X77617Y136138D01*
X77693Y135777D01*
X77617Y135415D01*
X77425Y135157D01*
X77118Y135002D01*
X76850Y134950D01*
G01X81367Y171950D02*
Y175050D01*
X80408D01*
X80102Y174895D01*
X79910Y174688D01*
X79833Y174275D01*
X79910Y173862D01*
X80140Y173603D01*
X80408Y173448D01*
X81367D01*
G01X80408D02*
X79833Y171950D01*
G01X78343Y172415D02*
X78113Y172157D01*
X77845Y172002D01*
X77500Y171950D01*
X77155Y172053D01*
X76887Y172260D01*
X76695Y172622D01*
X76657Y173035D01*
X76733Y173448D01*
X76925Y173707D01*
X77193Y173913D01*
X77462Y173965D01*
X77730Y173913D01*
X78075Y173707D01*
X77960Y175050D01*
X76925D01*
G01X74400Y171950D02*
X74132Y172002D01*
X73825Y172157D01*
X73633Y172415D01*
X73557Y172777D01*
X73633Y173138D01*
X73863Y173448D01*
X74208Y173603D01*
X74592D01*
X74822Y173707D01*
X75013Y173965D01*
X75090Y174327D01*
X74975Y174688D01*
X74707Y174947D01*
X74400Y175050D01*
X74093Y174947D01*
X73825Y174688D01*
X73710Y174327D01*
X73787Y173965D01*
X73978Y173707D01*
X74208Y173603D01*
X74592D01*
X74937Y173448D01*
X75167Y173138D01*
X75243Y172777D01*
X75167Y172415D01*
X74975Y172157D01*
X74668Y172002D01*
X74400Y171950D01*
G01X77417Y276950D02*
Y280050D01*
X76458D01*
X76152Y279895D01*
X75960Y279688D01*
X75883Y279275D01*
X75960Y278862D01*
X76190Y278603D01*
X76458Y278448D01*
X77417D01*
G01X76458D02*
X75883Y276950D01*
G01X74393Y277570D02*
X74163Y277208D01*
X73857Y277002D01*
X73512Y276950D01*
X73205Y277002D01*
X72898Y277260D01*
X72707Y277570D01*
X72668Y277880D01*
X72745Y278242D01*
X73013Y278500D01*
X73282Y278603D01*
X73627D01*
G01X73282D02*
X73052Y278758D01*
X72860Y279017D01*
X72783Y279327D01*
X72860Y279637D01*
X73052Y279895D01*
X73397Y280050D01*
X73742Y279998D01*
X74087Y279792D01*
G01X69990Y276950D02*
Y280050D01*
X71408Y277828D01*
X69492D01*
G01X67350Y280050D02*
X67657Y279947D01*
X67887Y279688D01*
X68040Y279378D01*
X68155Y278965D01*
X68193Y278500D01*
X68155Y278035D01*
X68040Y277622D01*
X67887Y277312D01*
X67657Y277053D01*
X67350Y276950D01*
X67043Y277053D01*
X66813Y277312D01*
X66660Y277622D01*
X66545Y278035D01*
X66507Y278500D01*
X66545Y278965D01*
X66660Y279378D01*
X66813Y279688D01*
X67043Y279947D01*
X67350Y280050D01*
G01X79950Y276583D02*
X83050D01*
Y277542D01*
X82895Y277848D01*
X82688Y278040D01*
X82275Y278117D01*
X81862Y278040D01*
X81603Y277810D01*
X81448Y277542D01*
Y276583D01*
G01Y277542D02*
X79950Y278117D01*
G01X80570Y279607D02*
X80208Y279837D01*
X80002Y280143D01*
X79950Y280488D01*
X80002Y280795D01*
X80260Y281102D01*
X80570Y281293D01*
X80880Y281332D01*
X81242Y281255D01*
X81500Y280987D01*
X81603Y280718D01*
Y280373D01*
G01Y280718D02*
X81758Y280948D01*
X82017Y281140D01*
X82327Y281217D01*
X82637Y281140D01*
X82895Y280948D01*
X83050Y280603D01*
X82998Y280258D01*
X82792Y279913D01*
G01X79950Y284010D02*
X83050D01*
X80828Y282592D01*
Y284508D01*
G01X80570Y285807D02*
X80208Y286037D01*
X80002Y286343D01*
X79950Y286688D01*
X80002Y286995D01*
X80260Y287302D01*
X80570Y287493D01*
X80880Y287532D01*
X81242Y287455D01*
X81500Y287187D01*
X81603Y286918D01*
Y286573D01*
G01Y286918D02*
X81758Y287148D01*
X82017Y287340D01*
X82327Y287417D01*
X82637Y287340D01*
X82895Y287148D01*
X83050Y286803D01*
X82998Y286458D01*
X82792Y286113D01*
G01X76950Y293583D02*
X80050D01*
Y294542D01*
X79895Y294848D01*
X79688Y295040D01*
X79275Y295117D01*
X78862Y295040D01*
X78603Y294810D01*
X78448Y294542D01*
Y293583D01*
G01Y294542D02*
X76950Y295117D01*
G01X77570Y296607D02*
X77208Y296837D01*
X77002Y297143D01*
X76950Y297488D01*
X77002Y297795D01*
X77260Y298102D01*
X77570Y298293D01*
X77880Y298332D01*
X78242Y298255D01*
X78500Y297987D01*
X78603Y297718D01*
Y297373D01*
G01Y297718D02*
X78758Y297948D01*
X79017Y298140D01*
X79327Y298217D01*
X79637Y298140D01*
X79895Y297948D01*
X80050Y297603D01*
X79998Y297258D01*
X79792Y296913D01*
G01X77570Y299707D02*
X77208Y299937D01*
X77002Y300243D01*
X76950Y300588D01*
X77002Y300895D01*
X77260Y301202D01*
X77570Y301393D01*
X77880Y301432D01*
X78242Y301355D01*
X78500Y301087D01*
X78603Y300818D01*
Y300473D01*
G01Y300818D02*
X78758Y301048D01*
X79017Y301240D01*
X79327Y301317D01*
X79637Y301240D01*
X79895Y301048D01*
X80050Y300703D01*
X79998Y300358D01*
X79792Y300013D01*
G01X79533Y302922D02*
X79843Y303152D01*
X79998Y303420D01*
X80050Y303727D01*
X79947Y304110D01*
X79688Y304378D01*
X79378Y304455D01*
X79068Y304417D01*
X78810Y304263D01*
X78293Y303497D01*
X77932Y303152D01*
X77415Y302922D01*
X76950Y302845D01*
Y304455D01*
G01X76292Y338743D02*
X76447Y338513D01*
X76550Y338245D01*
Y337938D01*
X76395Y337593D01*
X76137Y337325D01*
X75827Y337133D01*
X75310Y336980D01*
X74845Y336942D01*
X74380Y337018D01*
X74070Y337133D01*
X73760Y337363D01*
X73553Y337632D01*
X73450Y337900D01*
Y338168D01*
X73553Y338437D01*
X73708Y338667D01*
X73915Y338858D01*
G01X73812Y340348D02*
X73553Y340617D01*
X73450Y340923D01*
X73553Y341230D01*
X73863Y341498D01*
X74328Y341690D01*
X74793Y341767D01*
X75362D01*
X75827Y341690D01*
X76240Y341498D01*
X76447Y341268D01*
X76550Y341000D01*
X76447Y340693D01*
X76240Y340463D01*
X75930Y340310D01*
X75517Y340233D01*
X75155Y340310D01*
X74793Y340502D01*
X74587Y340732D01*
X74535Y341000D01*
X74638Y341307D01*
X74897Y341537D01*
X75362Y341767D01*
G01X73450Y344560D02*
X76550D01*
X74328Y343142D01*
Y345058D01*
G01X77950Y362083D02*
X81050D01*
Y363042D01*
X80895Y363348D01*
X80688Y363540D01*
X80275Y363617D01*
X79862Y363540D01*
X79603Y363310D01*
X79448Y363042D01*
Y362083D01*
G01Y363042D02*
X77950Y363617D01*
G01Y365950D02*
X81050D01*
X80430Y365490D01*
G01X77950D02*
Y366410D01*
G01X78570Y368207D02*
X78208Y368437D01*
X78002Y368743D01*
X77950Y369088D01*
X78002Y369395D01*
X78260Y369702D01*
X78570Y369893D01*
X78880Y369932D01*
X79242Y369855D01*
X79500Y369587D01*
X79603Y369318D01*
Y368973D01*
G01Y369318D02*
X79758Y369548D01*
X80017Y369740D01*
X80327Y369817D01*
X80637Y369740D01*
X80895Y369548D01*
X81050Y369203D01*
X80998Y368858D01*
X80792Y368513D01*
G01X81050Y372150D02*
X80947Y371843D01*
X80688Y371613D01*
X80378Y371460D01*
X79965Y371345D01*
X79500Y371307D01*
X79035Y371345D01*
X78622Y371460D01*
X78312Y371613D01*
X78053Y371843D01*
X77950Y372150D01*
X78053Y372457D01*
X78312Y372687D01*
X78622Y372840D01*
X79035Y372955D01*
X79500Y372993D01*
X79965Y372955D01*
X80378Y372840D01*
X80688Y372687D01*
X80947Y372457D01*
X81050Y372150D01*
G01X73450Y362083D02*
X76550D01*
Y363042D01*
X76395Y363348D01*
X76188Y363540D01*
X75775Y363617D01*
X75362Y363540D01*
X75103Y363310D01*
X74948Y363042D01*
Y362083D01*
G01Y363042D02*
X73450Y363617D01*
G01Y366410D02*
X76550D01*
X74328Y364992D01*
Y366908D01*
G01X74742Y368322D02*
X75103Y368590D01*
X75310Y368820D01*
X75413Y369127D01*
X75310Y369395D01*
X75103Y369587D01*
X74793Y369740D01*
X74432Y369778D01*
X74122Y369740D01*
X73812Y369587D01*
X73553Y369357D01*
X73450Y369088D01*
X73553Y368782D01*
X73863Y368513D01*
X74328Y368360D01*
X74845Y368322D01*
X75517Y368398D01*
X75878Y368513D01*
X76240Y368705D01*
X76498Y368973D01*
X76550Y369242D01*
X76447Y369510D01*
X76188Y369702D01*
G01X73450Y372073D02*
X74122Y372150D01*
X74690Y372265D01*
X75207Y372418D01*
X75775Y372610D01*
X76550Y372917D01*
Y371383D01*
G01X69450Y362083D02*
X72550D01*
Y363042D01*
X72395Y363348D01*
X72188Y363540D01*
X71775Y363617D01*
X71362Y363540D01*
X71103Y363310D01*
X70948Y363042D01*
Y362083D01*
G01Y363042D02*
X69450Y363617D01*
G01Y366410D02*
X72550D01*
X70328Y364992D01*
Y366908D01*
G01X70742Y368322D02*
X71103Y368590D01*
X71310Y368820D01*
X71413Y369127D01*
X71310Y369395D01*
X71103Y369587D01*
X70793Y369740D01*
X70432Y369778D01*
X70122Y369740D01*
X69812Y369587D01*
X69553Y369357D01*
X69450Y369088D01*
X69553Y368782D01*
X69863Y368513D01*
X70328Y368360D01*
X70845Y368322D01*
X71517Y368398D01*
X71878Y368513D01*
X72240Y368705D01*
X72498Y368973D01*
X72550Y369242D01*
X72447Y369510D01*
X72188Y369702D01*
G01X69450Y372150D02*
X69502Y372418D01*
X69657Y372725D01*
X69915Y372917D01*
X70277Y372993D01*
X70638Y372917D01*
X70948Y372687D01*
X71103Y372342D01*
Y371958D01*
X71207Y371728D01*
X71465Y371537D01*
X71827Y371460D01*
X72188Y371575D01*
X72447Y371843D01*
X72550Y372150D01*
X72447Y372457D01*
X72188Y372725D01*
X71827Y372840D01*
X71465Y372763D01*
X71207Y372572D01*
X71103Y372342D01*
Y371958D01*
X70948Y371613D01*
X70638Y371383D01*
X70277Y371307D01*
X69915Y371383D01*
X69657Y371575D01*
X69502Y371882D01*
X69450Y372150D01*
G01X86817Y58450D02*
Y61550D01*
X85858D01*
X85552Y61395D01*
X85360Y61188D01*
X85283Y60775D01*
X85360Y60362D01*
X85590Y60103D01*
X85858Y59948D01*
X86817D01*
G01X85858D02*
X85283Y58450D01*
G01X83793Y59070D02*
X83563Y58708D01*
X83257Y58502D01*
X82912Y58450D01*
X82605Y58502D01*
X82298Y58760D01*
X82107Y59070D01*
X82068Y59380D01*
X82145Y59742D01*
X82413Y60000D01*
X82682Y60103D01*
X83027D01*
G01X82682D02*
X82452Y60258D01*
X82260Y60517D01*
X82183Y60827D01*
X82260Y61137D01*
X82452Y61395D01*
X82797Y61550D01*
X83142Y61498D01*
X83487Y61292D01*
G01X91792Y76793D02*
X91947Y76563D01*
X92050Y76295D01*
Y75988D01*
X91895Y75643D01*
X91637Y75375D01*
X91327Y75183D01*
X90810Y75030D01*
X90345Y74992D01*
X89880Y75068D01*
X89570Y75183D01*
X89260Y75413D01*
X89053Y75682D01*
X88950Y75950D01*
Y76218D01*
X89053Y76487D01*
X89208Y76717D01*
X89415Y76908D01*
G01X88950Y79050D02*
X92050D01*
X91430Y78590D01*
G01X88950D02*
Y79510D01*
G01X99867Y69450D02*
Y72550D01*
X98908D01*
X98602Y72395D01*
X98410Y72188D01*
X98333Y71775D01*
X98410Y71362D01*
X98640Y71103D01*
X98908Y70948D01*
X99867D01*
G01X98908D02*
X98333Y69450D01*
G01X96728Y72033D02*
X96498Y72343D01*
X96230Y72498D01*
X95923Y72550D01*
X95540Y72447D01*
X95272Y72188D01*
X95195Y71878D01*
X95233Y71568D01*
X95387Y71310D01*
X96153Y70793D01*
X96498Y70432D01*
X96728Y69915D01*
X96805Y69450D01*
X95195D01*
G01X92440D02*
Y72550D01*
X93858Y70328D01*
X91942D01*
G01X86450Y98083D02*
X89550D01*
Y99042D01*
X89395Y99348D01*
X89188Y99540D01*
X88775Y99617D01*
X88362Y99540D01*
X88103Y99310D01*
X87948Y99042D01*
Y98083D01*
G01Y99042D02*
X86450Y99617D01*
G01Y101950D02*
X89550D01*
X88930Y101490D01*
G01X86450D02*
Y102410D01*
G01X86915Y104207D02*
X86657Y104437D01*
X86502Y104705D01*
X86450Y105050D01*
X86553Y105395D01*
X86760Y105663D01*
X87122Y105855D01*
X87535Y105893D01*
X87948Y105817D01*
X88207Y105625D01*
X88413Y105357D01*
X88465Y105088D01*
X88413Y104820D01*
X88207Y104475D01*
X89550Y104590D01*
Y105625D01*
G01X86812Y107498D02*
X86553Y107767D01*
X86450Y108073D01*
X86553Y108380D01*
X86863Y108648D01*
X87328Y108840D01*
X87793Y108917D01*
X88362D01*
X88827Y108840D01*
X89240Y108648D01*
X89447Y108418D01*
X89550Y108150D01*
X89447Y107843D01*
X89240Y107613D01*
X88930Y107460D01*
X88517Y107383D01*
X88155Y107460D01*
X87793Y107652D01*
X87587Y107882D01*
X87535Y108150D01*
X87638Y108457D01*
X87897Y108687D01*
X88362Y108917D01*
G01X82450Y103083D02*
X85550D01*
Y104042D01*
X85395Y104348D01*
X85188Y104540D01*
X84775Y104617D01*
X84362Y104540D01*
X84103Y104310D01*
X83948Y104042D01*
Y103083D01*
G01Y104042D02*
X82450Y104617D01*
G01Y106950D02*
X85550D01*
X84930Y106490D01*
G01X82450D02*
Y107410D01*
G01X83742Y109322D02*
X84103Y109590D01*
X84310Y109820D01*
X84413Y110127D01*
X84310Y110395D01*
X84103Y110587D01*
X83793Y110740D01*
X83432Y110778D01*
X83122Y110740D01*
X82812Y110587D01*
X82553Y110357D01*
X82450Y110088D01*
X82553Y109782D01*
X82863Y109513D01*
X83328Y109360D01*
X83845Y109322D01*
X84517Y109398D01*
X84878Y109513D01*
X85240Y109705D01*
X85498Y109973D01*
X85550Y110242D01*
X85447Y110510D01*
X85188Y110702D01*
G01X82450Y113150D02*
X85550D01*
X84930Y112690D01*
G01X82450D02*
Y113610D01*
G01X90950Y224583D02*
X94050D01*
Y225542D01*
X93895Y225848D01*
X93688Y226040D01*
X93275Y226117D01*
X92862Y226040D01*
X92603Y225810D01*
X92448Y225542D01*
Y224583D01*
G01Y225542D02*
X90950Y226117D01*
G01X91570Y227607D02*
X91208Y227837D01*
X91002Y228143D01*
X90950Y228488D01*
X91002Y228795D01*
X91260Y229102D01*
X91570Y229293D01*
X91880Y229332D01*
X92242Y229255D01*
X92500Y228987D01*
X92603Y228718D01*
Y228373D01*
G01Y228718D02*
X92758Y228948D01*
X93017Y229140D01*
X93327Y229217D01*
X93637Y229140D01*
X93895Y228948D01*
X94050Y228603D01*
X93998Y228258D01*
X93792Y227913D01*
G01X90950Y231550D02*
X94050D01*
X93430Y231090D01*
G01X90950D02*
Y232010D01*
G01Y235110D02*
X94050D01*
X91828Y233692D01*
Y235608D01*
G01X86950Y224583D02*
X90050D01*
Y225542D01*
X89895Y225848D01*
X89688Y226040D01*
X89275Y226117D01*
X88862Y226040D01*
X88603Y225810D01*
X88448Y225542D01*
Y224583D01*
G01Y225542D02*
X86950Y226117D01*
G01X89533Y227722D02*
X89843Y227952D01*
X89998Y228220D01*
X90050Y228527D01*
X89947Y228910D01*
X89688Y229178D01*
X89378Y229255D01*
X89068Y229217D01*
X88810Y229063D01*
X88293Y228297D01*
X87932Y227952D01*
X87415Y227722D01*
X86950Y227645D01*
Y229255D01*
G01Y231550D02*
X87002Y231818D01*
X87157Y232125D01*
X87415Y232317D01*
X87777Y232393D01*
X88138Y232317D01*
X88448Y232087D01*
X88603Y231742D01*
Y231358D01*
X88707Y231128D01*
X88965Y230937D01*
X89327Y230860D01*
X89688Y230975D01*
X89947Y231243D01*
X90050Y231550D01*
X89947Y231857D01*
X89688Y232125D01*
X89327Y232240D01*
X88965Y232163D01*
X88707Y231972D01*
X88603Y231742D01*
Y231358D01*
X88448Y231013D01*
X88138Y230783D01*
X87777Y230707D01*
X87415Y230783D01*
X87157Y230975D01*
X87002Y231282D01*
X86950Y231550D01*
G01Y234650D02*
X90050D01*
X89430Y234190D01*
G01X86950D02*
Y235110D01*
G01X93450Y269633D02*
X96550D01*
Y270592D01*
X96395Y270898D01*
X96188Y271090D01*
X95775Y271167D01*
X95362Y271090D01*
X95103Y270860D01*
X94948Y270592D01*
Y269633D01*
G01Y270592D02*
X93450Y271167D01*
G01X93812Y272848D02*
X93553Y273117D01*
X93450Y273423D01*
X93553Y273730D01*
X93863Y273998D01*
X94328Y274190D01*
X94793Y274267D01*
X95362D01*
X95827Y274190D01*
X96240Y273998D01*
X96447Y273768D01*
X96550Y273500D01*
X96447Y273193D01*
X96240Y272963D01*
X95930Y272810D01*
X95517Y272733D01*
X95155Y272810D01*
X94793Y273002D01*
X94587Y273232D01*
X94535Y273500D01*
X94638Y273807D01*
X94897Y274037D01*
X95362Y274267D01*
G01X93450Y276600D02*
X96550D01*
X95930Y276140D01*
G01X93450D02*
Y277060D01*
G01X92417Y321450D02*
Y324550D01*
X91458D01*
X91152Y324395D01*
X90960Y324188D01*
X90883Y323775D01*
X90960Y323362D01*
X91190Y323103D01*
X91458Y322948D01*
X92417D01*
G01X91458D02*
X90883Y321450D01*
G01X88090D02*
Y324550D01*
X89508Y322328D01*
X87592D01*
G01X85527Y321450D02*
X85450Y322122D01*
X85335Y322690D01*
X85182Y323207D01*
X84990Y323775D01*
X84683Y324550D01*
X86217D01*
G01X82350Y321450D02*
X82082Y321502D01*
X81775Y321657D01*
X81583Y321915D01*
X81507Y322277D01*
X81583Y322638D01*
X81813Y322948D01*
X82158Y323103D01*
X82542D01*
X82772Y323207D01*
X82963Y323465D01*
X83040Y323827D01*
X82925Y324188D01*
X82657Y324447D01*
X82350Y324550D01*
X82043Y324447D01*
X81775Y324188D01*
X81660Y323827D01*
X81737Y323465D01*
X81928Y323207D01*
X82158Y323103D01*
X82542D01*
X82887Y322948D01*
X83117Y322638D01*
X83193Y322277D01*
X83117Y321915D01*
X82925Y321657D01*
X82618Y321502D01*
X82350Y321450D01*
G01X92917Y316950D02*
Y320050D01*
X91958D01*
X91652Y319895D01*
X91460Y319688D01*
X91383Y319275D01*
X91460Y318862D01*
X91690Y318603D01*
X91958Y318448D01*
X92917D01*
G01X91958D02*
X91383Y316950D01*
G01X88590D02*
Y320050D01*
X90008Y317828D01*
X88092D01*
G01X86027Y316950D02*
X85950Y317622D01*
X85835Y318190D01*
X85682Y318707D01*
X85490Y319275D01*
X85183Y320050D01*
X86717D01*
G01X83502Y317312D02*
X83233Y317053D01*
X82927Y316950D01*
X82620Y317053D01*
X82352Y317363D01*
X82160Y317828D01*
X82083Y318293D01*
Y318862D01*
X82160Y319327D01*
X82352Y319740D01*
X82582Y319947D01*
X82850Y320050D01*
X83157Y319947D01*
X83387Y319740D01*
X83540Y319430D01*
X83617Y319017D01*
X83540Y318655D01*
X83348Y318293D01*
X83118Y318087D01*
X82850Y318035D01*
X82543Y318138D01*
X82313Y318397D01*
X82083Y318862D01*
G01X92917Y312950D02*
Y316050D01*
X91958D01*
X91652Y315895D01*
X91460Y315688D01*
X91383Y315275D01*
X91460Y314862D01*
X91690Y314603D01*
X91958Y314448D01*
X92917D01*
G01X91958D02*
X91383Y312950D01*
G01X88590D02*
Y316050D01*
X90008Y313828D01*
X88092D01*
G01X86027Y312950D02*
X85950Y313622D01*
X85835Y314190D01*
X85682Y314707D01*
X85490Y315275D01*
X85183Y316050D01*
X86717D01*
G01X83693Y313570D02*
X83463Y313208D01*
X83157Y313002D01*
X82812Y312950D01*
X82505Y313002D01*
X82198Y313260D01*
X82007Y313570D01*
X81968Y313880D01*
X82045Y314242D01*
X82313Y314500D01*
X82582Y314603D01*
X82927D01*
G01X82582D02*
X82352Y314758D01*
X82160Y315017D01*
X82083Y315327D01*
X82160Y315637D01*
X82352Y315895D01*
X82697Y316050D01*
X83042Y315998D01*
X83387Y315792D01*
G01X100292Y309243D02*
X100447Y309013D01*
X100550Y308745D01*
Y308438D01*
X100395Y308093D01*
X100137Y307825D01*
X99827Y307633D01*
X99310Y307480D01*
X98845Y307442D01*
X98380Y307518D01*
X98070Y307633D01*
X97760Y307863D01*
X97553Y308132D01*
X97450Y308400D01*
Y308668D01*
X97553Y308937D01*
X97708Y309167D01*
X97915Y309358D01*
G01X97812Y310848D02*
X97553Y311117D01*
X97450Y311423D01*
X97553Y311730D01*
X97863Y311998D01*
X98328Y312190D01*
X98793Y312267D01*
X99362D01*
X99827Y312190D01*
X100240Y311998D01*
X100447Y311768D01*
X100550Y311500D01*
X100447Y311193D01*
X100240Y310963D01*
X99930Y310810D01*
X99517Y310733D01*
X99155Y310810D01*
X98793Y311002D01*
X98587Y311232D01*
X98535Y311500D01*
X98638Y311807D01*
X98897Y312037D01*
X99362Y312267D01*
G01X100550Y314600D02*
X100447Y314293D01*
X100188Y314063D01*
X99878Y313910D01*
X99465Y313795D01*
X99000Y313757D01*
X98535Y313795D01*
X98122Y313910D01*
X97812Y314063D01*
X97553Y314293D01*
X97450Y314600D01*
X97553Y314907D01*
X97812Y315137D01*
X98122Y315290D01*
X98535Y315405D01*
X99000Y315443D01*
X99465Y315405D01*
X99878Y315290D01*
X100188Y315137D01*
X100447Y314907D01*
X100550Y314600D01*
G01X98417Y330450D02*
Y333550D01*
X97458D01*
X97152Y333395D01*
X96960Y333188D01*
X96883Y332775D01*
X96960Y332362D01*
X97190Y332103D01*
X97458Y331948D01*
X98417D01*
G01X97458D02*
X96883Y330450D01*
G01X94090D02*
Y333550D01*
X95508Y331328D01*
X93592D01*
G01X92178Y331742D02*
X91910Y332103D01*
X91680Y332310D01*
X91373Y332413D01*
X91105Y332310D01*
X90913Y332103D01*
X90760Y331793D01*
X90722Y331432D01*
X90760Y331122D01*
X90913Y330812D01*
X91143Y330553D01*
X91412Y330450D01*
X91718Y330553D01*
X91987Y330863D01*
X92140Y331328D01*
X92178Y331845D01*
X92102Y332517D01*
X91987Y332878D01*
X91795Y333240D01*
X91527Y333498D01*
X91258Y333550D01*
X90990Y333447D01*
X90798Y333188D01*
G01X89078Y331742D02*
X88810Y332103D01*
X88580Y332310D01*
X88273Y332413D01*
X88005Y332310D01*
X87813Y332103D01*
X87660Y331793D01*
X87622Y331432D01*
X87660Y331122D01*
X87813Y330812D01*
X88043Y330553D01*
X88312Y330450D01*
X88618Y330553D01*
X88887Y330863D01*
X89040Y331328D01*
X89078Y331845D01*
X89002Y332517D01*
X88887Y332878D01*
X88695Y333240D01*
X88427Y333498D01*
X88158Y333550D01*
X87890Y333447D01*
X87698Y333188D01*
G01X98417Y334450D02*
Y337550D01*
X97458D01*
X97152Y337395D01*
X96960Y337188D01*
X96883Y336775D01*
X96960Y336362D01*
X97190Y336103D01*
X97458Y335948D01*
X98417D01*
G01X97458D02*
X96883Y334450D01*
G01X94090D02*
Y337550D01*
X95508Y335328D01*
X93592D01*
G01X92178Y335742D02*
X91910Y336103D01*
X91680Y336310D01*
X91373Y336413D01*
X91105Y336310D01*
X90913Y336103D01*
X90760Y335793D01*
X90722Y335432D01*
X90760Y335122D01*
X90913Y334812D01*
X91143Y334553D01*
X91412Y334450D01*
X91718Y334553D01*
X91987Y334863D01*
X92140Y335328D01*
X92178Y335845D01*
X92102Y336517D01*
X91987Y336878D01*
X91795Y337240D01*
X91527Y337498D01*
X91258Y337550D01*
X90990Y337447D01*
X90798Y337188D01*
G01X89002Y334812D02*
X88733Y334553D01*
X88427Y334450D01*
X88120Y334553D01*
X87852Y334863D01*
X87660Y335328D01*
X87583Y335793D01*
Y336362D01*
X87660Y336827D01*
X87852Y337240D01*
X88082Y337447D01*
X88350Y337550D01*
X88657Y337447D01*
X88887Y337240D01*
X89040Y336930D01*
X89117Y336517D01*
X89040Y336155D01*
X88848Y335793D01*
X88618Y335587D01*
X88350Y335535D01*
X88043Y335638D01*
X87813Y335897D01*
X87583Y336362D01*
G01X98417Y326450D02*
Y329550D01*
X97458D01*
X97152Y329395D01*
X96960Y329188D01*
X96883Y328775D01*
X96960Y328362D01*
X97190Y328103D01*
X97458Y327948D01*
X98417D01*
G01X97458D02*
X96883Y326450D01*
G01X94090D02*
Y329550D01*
X95508Y327328D01*
X93592D01*
G01X91527Y326450D02*
X91450Y327122D01*
X91335Y327690D01*
X91182Y328207D01*
X90990Y328775D01*
X90683Y329550D01*
X92217D01*
G01X88350D02*
X88657Y329447D01*
X88887Y329188D01*
X89040Y328878D01*
X89155Y328465D01*
X89193Y328000D01*
X89155Y327535D01*
X89040Y327122D01*
X88887Y326812D01*
X88657Y326553D01*
X88350Y326450D01*
X88043Y326553D01*
X87813Y326812D01*
X87660Y327122D01*
X87545Y327535D01*
X87507Y328000D01*
X87545Y328465D01*
X87660Y328878D01*
X87813Y329188D01*
X88043Y329447D01*
X88350Y329550D01*
G01X82450Y362083D02*
X85550D01*
Y363042D01*
X85395Y363348D01*
X85188Y363540D01*
X84775Y363617D01*
X84362Y363540D01*
X84103Y363310D01*
X83948Y363042D01*
Y362083D01*
G01Y363042D02*
X82450Y363617D01*
G01Y366410D02*
X85550D01*
X83328Y364992D01*
Y366908D01*
G01X83742Y368322D02*
X84103Y368590D01*
X84310Y368820D01*
X84413Y369127D01*
X84310Y369395D01*
X84103Y369587D01*
X83793Y369740D01*
X83432Y369778D01*
X83122Y369740D01*
X82812Y369587D01*
X82553Y369357D01*
X82450Y369088D01*
X82553Y368782D01*
X82863Y368513D01*
X83328Y368360D01*
X83845Y368322D01*
X84517Y368398D01*
X84878Y368513D01*
X85240Y368705D01*
X85498Y368973D01*
X85550Y369242D01*
X85447Y369510D01*
X85188Y369702D01*
G01X85550Y372150D02*
X85447Y371843D01*
X85188Y371613D01*
X84878Y371460D01*
X84465Y371345D01*
X84000Y371307D01*
X83535Y371345D01*
X83122Y371460D01*
X82812Y371613D01*
X82553Y371843D01*
X82450Y372150D01*
X82553Y372457D01*
X82812Y372687D01*
X83122Y372840D01*
X83535Y372955D01*
X84000Y372993D01*
X84465Y372955D01*
X84878Y372840D01*
X85188Y372687D01*
X85447Y372457D01*
X85550Y372150D01*
G01X123467Y59450D02*
Y62550D01*
X122508D01*
X122202Y62395D01*
X122010Y62188D01*
X121933Y61775D01*
X122010Y61362D01*
X122240Y61103D01*
X122508Y60948D01*
X123467D01*
G01X122508D02*
X121933Y59450D01*
G01X119600D02*
Y62550D01*
X120060Y61930D01*
G01Y59450D02*
X119140D01*
G01X117152Y59812D02*
X116883Y59553D01*
X116577Y59450D01*
X116270Y59553D01*
X116002Y59863D01*
X115810Y60328D01*
X115733Y60793D01*
Y61362D01*
X115810Y61827D01*
X116002Y62240D01*
X116232Y62447D01*
X116500Y62550D01*
X116807Y62447D01*
X117037Y62240D01*
X117190Y61930D01*
X117267Y61517D01*
X117190Y61155D01*
X116998Y60793D01*
X116768Y60587D01*
X116500Y60535D01*
X116193Y60638D01*
X115963Y60897D01*
X115733Y61362D01*
G01X114052Y59812D02*
X113783Y59553D01*
X113477Y59450D01*
X113170Y59553D01*
X112902Y59863D01*
X112710Y60328D01*
X112633Y60793D01*
Y61362D01*
X112710Y61827D01*
X112902Y62240D01*
X113132Y62447D01*
X113400Y62550D01*
X113707Y62447D01*
X113937Y62240D01*
X114090Y61930D01*
X114167Y61517D01*
X114090Y61155D01*
X113898Y60793D01*
X113668Y60587D01*
X113400Y60535D01*
X113093Y60638D01*
X112863Y60897D01*
X112633Y61362D01*
G01X110300Y59450D02*
Y62550D01*
X110760Y61930D01*
G01Y59450D02*
X109840D01*
G01X110417Y64950D02*
Y68050D01*
X109458D01*
X109152Y67895D01*
X108960Y67688D01*
X108883Y67275D01*
X108960Y66862D01*
X109190Y66603D01*
X109458Y66448D01*
X110417D01*
G01X109458D02*
X108883Y64950D01*
G01X107393Y65570D02*
X107163Y65208D01*
X106857Y65002D01*
X106512Y64950D01*
X106205Y65002D01*
X105898Y65260D01*
X105707Y65570D01*
X105668Y65880D01*
X105745Y66242D01*
X106013Y66500D01*
X106282Y66603D01*
X106627D01*
G01X106282D02*
X106052Y66758D01*
X105860Y67017D01*
X105783Y67327D01*
X105860Y67637D01*
X106052Y67895D01*
X106397Y68050D01*
X106742Y67998D01*
X107087Y67792D01*
G01X102990Y64950D02*
Y68050D01*
X104408Y65828D01*
X102492D01*
G01X99890Y64950D02*
Y68050D01*
X101308Y65828D01*
X99392D01*
G01X110550Y337183D02*
X107450D01*
Y338717D01*
G01Y341510D02*
X110550D01*
X108328Y340092D01*
Y342008D01*
G01X121257Y343792D02*
X121487Y343947D01*
X121755Y344050D01*
X122062D01*
X122407Y343895D01*
X122675Y343637D01*
X122867Y343327D01*
X123020Y342810D01*
X123058Y342345D01*
X122982Y341880D01*
X122867Y341570D01*
X122637Y341260D01*
X122368Y341053D01*
X122100Y340950D01*
X121832D01*
X121563Y341053D01*
X121333Y341208D01*
X121142Y341415D01*
G01X119652Y341312D02*
X119383Y341053D01*
X119077Y340950D01*
X118770Y341053D01*
X118502Y341363D01*
X118310Y341828D01*
X118233Y342293D01*
Y342862D01*
X118310Y343327D01*
X118502Y343740D01*
X118732Y343947D01*
X119000Y344050D01*
X119307Y343947D01*
X119537Y343740D01*
X119690Y343430D01*
X119767Y343017D01*
X119690Y342655D01*
X119498Y342293D01*
X119268Y342087D01*
X119000Y342035D01*
X118693Y342138D01*
X118463Y342397D01*
X118233Y342862D01*
G01X116743Y341415D02*
X116513Y341157D01*
X116245Y341002D01*
X115900Y340950D01*
X115555Y341053D01*
X115287Y341260D01*
X115095Y341622D01*
X115057Y342035D01*
X115133Y342448D01*
X115325Y342707D01*
X115593Y342913D01*
X115862Y342965D01*
X116130Y342913D01*
X116475Y342707D01*
X116360Y344050D01*
X115325D01*
G01X114792Y367193D02*
X114947Y366963D01*
X115050Y366695D01*
Y366388D01*
X114895Y366043D01*
X114637Y365775D01*
X114327Y365583D01*
X113810Y365430D01*
X113345Y365392D01*
X112880Y365468D01*
X112570Y365583D01*
X112260Y365813D01*
X112053Y366082D01*
X111950Y366350D01*
Y366618D01*
X112053Y366887D01*
X112208Y367117D01*
X112415Y367308D01*
G01X111950Y369450D02*
X115050D01*
X114430Y368990D01*
G01X111950D02*
Y369910D01*
G01X115050Y372550D02*
X114947Y372243D01*
X114688Y372013D01*
X114378Y371860D01*
X113965Y371745D01*
X113500Y371707D01*
X113035Y371745D01*
X112622Y371860D01*
X112312Y372013D01*
X112053Y372243D01*
X111950Y372550D01*
X112053Y372857D01*
X112312Y373087D01*
X112622Y373240D01*
X113035Y373355D01*
X113500Y373393D01*
X113965Y373355D01*
X114378Y373240D01*
X114688Y373087D01*
X114947Y372857D01*
X115050Y372550D01*
G01Y375650D02*
X114947Y375343D01*
X114688Y375113D01*
X114378Y374960D01*
X113965Y374845D01*
X113500Y374807D01*
X113035Y374845D01*
X112622Y374960D01*
X112312Y375113D01*
X112053Y375343D01*
X111950Y375650D01*
X112053Y375957D01*
X112312Y376187D01*
X112622Y376340D01*
X113035Y376455D01*
X113500Y376493D01*
X113965Y376455D01*
X114378Y376340D01*
X114688Y376187D01*
X114947Y375957D01*
X115050Y375650D01*
G01X110792Y367243D02*
X110947Y367013D01*
X111050Y366745D01*
Y366438D01*
X110895Y366093D01*
X110637Y365825D01*
X110327Y365633D01*
X109810Y365480D01*
X109345Y365442D01*
X108880Y365518D01*
X108570Y365633D01*
X108260Y365863D01*
X108053Y366132D01*
X107950Y366400D01*
Y366668D01*
X108053Y366937D01*
X108208Y367167D01*
X108415Y367358D01*
G01X108312Y368848D02*
X108053Y369117D01*
X107950Y369423D01*
X108053Y369730D01*
X108363Y369998D01*
X108828Y370190D01*
X109293Y370267D01*
X109862D01*
X110327Y370190D01*
X110740Y369998D01*
X110947Y369768D01*
X111050Y369500D01*
X110947Y369193D01*
X110740Y368963D01*
X110430Y368810D01*
X110017Y368733D01*
X109655Y368810D01*
X109293Y369002D01*
X109087Y369232D01*
X109035Y369500D01*
X109138Y369807D01*
X109397Y370037D01*
X109862Y370267D01*
G01X107950Y372600D02*
X108002Y372868D01*
X108157Y373175D01*
X108415Y373367D01*
X108777Y373443D01*
X109138Y373367D01*
X109448Y373137D01*
X109603Y372792D01*
Y372408D01*
X109707Y372178D01*
X109965Y371987D01*
X110327Y371910D01*
X110688Y372025D01*
X110947Y372293D01*
X111050Y372600D01*
X110947Y372907D01*
X110688Y373175D01*
X110327Y373290D01*
X109965Y373213D01*
X109707Y373022D01*
X109603Y372792D01*
Y372408D01*
X109448Y372063D01*
X109138Y371833D01*
X108777Y371757D01*
X108415Y371833D01*
X108157Y372025D01*
X108002Y372332D01*
X107950Y372600D01*
G01X105450Y377133D02*
X108550D01*
Y378092D01*
X108395Y378398D01*
X108188Y378590D01*
X107775Y378667D01*
X107362Y378590D01*
X107103Y378360D01*
X106948Y378092D01*
Y377133D01*
G01Y378092D02*
X105450Y378667D01*
G01Y381000D02*
X108550D01*
X107930Y380540D01*
G01X105450D02*
Y381460D01*
G01Y384100D02*
X105502Y384368D01*
X105657Y384675D01*
X105915Y384867D01*
X106277Y384943D01*
X106638Y384867D01*
X106948Y384637D01*
X107103Y384292D01*
Y383908D01*
X107207Y383678D01*
X107465Y383487D01*
X107827Y383410D01*
X108188Y383525D01*
X108447Y383793D01*
X108550Y384100D01*
X108447Y384407D01*
X108188Y384675D01*
X107827Y384790D01*
X107465Y384713D01*
X107207Y384522D01*
X107103Y384292D01*
Y383908D01*
X106948Y383563D01*
X106638Y383333D01*
X106277Y383257D01*
X105915Y383333D01*
X105657Y383525D01*
X105502Y383832D01*
X105450Y384100D01*
G01X141417Y56950D02*
Y60050D01*
X140458D01*
X140152Y59895D01*
X139960Y59688D01*
X139883Y59275D01*
X139960Y58862D01*
X140190Y58603D01*
X140458Y58448D01*
X141417D01*
G01X140458D02*
X139883Y56950D01*
G01X137550D02*
Y60050D01*
X138010Y59430D01*
G01Y56950D02*
X137090D01*
G01X134527D02*
X134450Y57622D01*
X134335Y58190D01*
X134182Y58707D01*
X133990Y59275D01*
X133683Y60050D01*
X135217D01*
G01X132193Y57415D02*
X131963Y57157D01*
X131695Y57002D01*
X131350Y56950D01*
X131005Y57053D01*
X130737Y57260D01*
X130545Y57622D01*
X130507Y58035D01*
X130583Y58448D01*
X130775Y58707D01*
X131043Y58913D01*
X131312Y58965D01*
X131580Y58913D01*
X131925Y58707D01*
X131810Y60050D01*
X130775D01*
G01X122317Y73950D02*
Y77050D01*
X121358D01*
X121052Y76895D01*
X120860Y76688D01*
X120783Y76275D01*
X120860Y75862D01*
X121090Y75603D01*
X121358Y75448D01*
X122317D01*
G01X121358D02*
X120783Y73950D01*
G01X118450D02*
Y77050D01*
X118910Y76430D01*
G01Y73950D02*
X117990D01*
G01X130950Y307083D02*
X134050D01*
Y308042D01*
X133895Y308348D01*
X133688Y308540D01*
X133275Y308617D01*
X132862Y308540D01*
X132603Y308310D01*
X132448Y308042D01*
Y307083D01*
G01Y308042D02*
X130950Y308617D01*
G01Y310950D02*
X134050D01*
X133430Y310490D01*
G01X130950D02*
Y311410D01*
G01X131570Y313207D02*
X131208Y313437D01*
X131002Y313743D01*
X130950Y314088D01*
X131002Y314395D01*
X131260Y314702D01*
X131570Y314893D01*
X131880Y314932D01*
X132242Y314855D01*
X132500Y314587D01*
X132603Y314318D01*
Y313973D01*
G01Y314318D02*
X132758Y314548D01*
X133017Y314740D01*
X133327Y314817D01*
X133637Y314740D01*
X133895Y314548D01*
X134050Y314203D01*
X133998Y313858D01*
X133792Y313513D01*
G01X130950Y317150D02*
X134050D01*
X133430Y316690D01*
G01X130950D02*
Y317610D01*
G01X139917Y335950D02*
Y339050D01*
X138958D01*
X138652Y338895D01*
X138460Y338688D01*
X138383Y338275D01*
X138460Y337862D01*
X138690Y337603D01*
X138958Y337448D01*
X139917D01*
G01X138958D02*
X138383Y335950D01*
G01X136050D02*
Y339050D01*
X136510Y338430D01*
G01Y335950D02*
X135590D01*
G01X133793Y336570D02*
X133563Y336208D01*
X133257Y336002D01*
X132912Y335950D01*
X132605Y336002D01*
X132298Y336260D01*
X132107Y336570D01*
X132068Y336880D01*
X132145Y337242D01*
X132413Y337500D01*
X132682Y337603D01*
X133027D01*
G01X132682D02*
X132452Y337758D01*
X132260Y338017D01*
X132183Y338327D01*
X132260Y338637D01*
X132452Y338895D01*
X132797Y339050D01*
X133142Y338998D01*
X133487Y338792D01*
G01X130578Y338533D02*
X130348Y338843D01*
X130080Y338998D01*
X129773Y339050D01*
X129390Y338947D01*
X129122Y338688D01*
X129045Y338378D01*
X129083Y338068D01*
X129237Y337810D01*
X130003Y337293D01*
X130348Y336932D01*
X130578Y336415D01*
X130655Y335950D01*
X129045D01*
G01X139917Y331450D02*
Y334550D01*
X138958D01*
X138652Y334395D01*
X138460Y334188D01*
X138383Y333775D01*
X138460Y333362D01*
X138690Y333103D01*
X138958Y332948D01*
X139917D01*
G01X138958D02*
X138383Y331450D01*
G01X136893Y332070D02*
X136663Y331708D01*
X136357Y331502D01*
X136012Y331450D01*
X135705Y331502D01*
X135398Y331760D01*
X135207Y332070D01*
X135168Y332380D01*
X135245Y332742D01*
X135513Y333000D01*
X135782Y333103D01*
X136127D01*
G01X135782D02*
X135552Y333258D01*
X135360Y333517D01*
X135283Y333827D01*
X135360Y334137D01*
X135552Y334395D01*
X135897Y334550D01*
X136242Y334498D01*
X136587Y334292D01*
G01X132490Y331450D02*
Y334550D01*
X133908Y332328D01*
X131992D01*
G01X130502Y331812D02*
X130233Y331553D01*
X129927Y331450D01*
X129620Y331553D01*
X129352Y331863D01*
X129160Y332328D01*
X129083Y332793D01*
Y333362D01*
X129160Y333827D01*
X129352Y334240D01*
X129582Y334447D01*
X129850Y334550D01*
X130157Y334447D01*
X130387Y334240D01*
X130540Y333930D01*
X130617Y333517D01*
X130540Y333155D01*
X130348Y332793D01*
X130118Y332587D01*
X129850Y332535D01*
X129543Y332638D01*
X129313Y332897D01*
X129083Y333362D01*
G01X138257Y346792D02*
X138487Y346947D01*
X138755Y347050D01*
X139062D01*
X139407Y346895D01*
X139675Y346637D01*
X139867Y346327D01*
X140020Y345810D01*
X140058Y345345D01*
X139982Y344880D01*
X139867Y344570D01*
X139637Y344260D01*
X139368Y344053D01*
X139100Y343950D01*
X138832D01*
X138563Y344053D01*
X138333Y344208D01*
X138142Y344415D01*
G01X136652Y344312D02*
X136383Y344053D01*
X136077Y343950D01*
X135770Y344053D01*
X135502Y344363D01*
X135310Y344828D01*
X135233Y345293D01*
Y345862D01*
X135310Y346327D01*
X135502Y346740D01*
X135732Y346947D01*
X136000Y347050D01*
X136307Y346947D01*
X136537Y346740D01*
X136690Y346430D01*
X136767Y346017D01*
X136690Y345655D01*
X136498Y345293D01*
X136268Y345087D01*
X136000Y345035D01*
X135693Y345138D01*
X135463Y345397D01*
X135233Y345862D01*
G01X133628Y345242D02*
X133360Y345603D01*
X133130Y345810D01*
X132823Y345913D01*
X132555Y345810D01*
X132363Y345603D01*
X132210Y345293D01*
X132172Y344932D01*
X132210Y344622D01*
X132363Y344312D01*
X132593Y344053D01*
X132862Y343950D01*
X133168Y344053D01*
X133437Y344363D01*
X133590Y344828D01*
X133628Y345345D01*
X133552Y346017D01*
X133437Y346378D01*
X133245Y346740D01*
X132977Y346998D01*
X132708Y347050D01*
X132440Y346947D01*
X132248Y346688D01*
G01X128292Y367193D02*
X128447Y366963D01*
X128550Y366695D01*
Y366388D01*
X128395Y366043D01*
X128137Y365775D01*
X127827Y365583D01*
X127310Y365430D01*
X126845Y365392D01*
X126380Y365468D01*
X126070Y365583D01*
X125760Y365813D01*
X125553Y366082D01*
X125450Y366350D01*
Y366618D01*
X125553Y366887D01*
X125708Y367117D01*
X125915Y367308D01*
G01X125450Y369450D02*
X128550D01*
X127930Y368990D01*
G01X125450D02*
Y369910D01*
G01X128550Y372550D02*
X128447Y372243D01*
X128188Y372013D01*
X127878Y371860D01*
X127465Y371745D01*
X127000Y371707D01*
X126535Y371745D01*
X126122Y371860D01*
X125812Y372013D01*
X125553Y372243D01*
X125450Y372550D01*
X125553Y372857D01*
X125812Y373087D01*
X126122Y373240D01*
X126535Y373355D01*
X127000Y373393D01*
X127465Y373355D01*
X127878Y373240D01*
X128188Y373087D01*
X128447Y372857D01*
X128550Y372550D01*
G01X125450Y375650D02*
X128550D01*
X127930Y375190D01*
G01X125450D02*
Y376110D01*
G01X115950Y365583D02*
X119050D01*
Y366542D01*
X118895Y366848D01*
X118688Y367040D01*
X118275Y367117D01*
X117862Y367040D01*
X117603Y366810D01*
X117448Y366542D01*
Y365583D01*
G01Y366542D02*
X115950Y367117D01*
G01Y369910D02*
X119050D01*
X116828Y368492D01*
Y370408D01*
G01X117242Y371822D02*
X117603Y372090D01*
X117810Y372320D01*
X117913Y372627D01*
X117810Y372895D01*
X117603Y373087D01*
X117293Y373240D01*
X116932Y373278D01*
X116622Y373240D01*
X116312Y373087D01*
X116053Y372857D01*
X115950Y372588D01*
X116053Y372282D01*
X116363Y372013D01*
X116828Y371860D01*
X117345Y371822D01*
X118017Y371898D01*
X118378Y372013D01*
X118740Y372205D01*
X118998Y372473D01*
X119050Y372742D01*
X118947Y373010D01*
X118688Y373202D01*
G01X116570Y374807D02*
X116208Y375037D01*
X116002Y375343D01*
X115950Y375688D01*
X116002Y375995D01*
X116260Y376302D01*
X116570Y376493D01*
X116880Y376532D01*
X117242Y376455D01*
X117500Y376187D01*
X117603Y375918D01*
Y375573D01*
G01Y375918D02*
X117758Y376148D01*
X118017Y376340D01*
X118327Y376417D01*
X118637Y376340D01*
X118895Y376148D01*
X119050Y375803D01*
X118998Y375458D01*
X118792Y375113D01*
G01X124292Y367243D02*
X124447Y367013D01*
X124550Y366745D01*
Y366438D01*
X124395Y366093D01*
X124137Y365825D01*
X123827Y365633D01*
X123310Y365480D01*
X122845Y365442D01*
X122380Y365518D01*
X122070Y365633D01*
X121760Y365863D01*
X121553Y366132D01*
X121450Y366400D01*
Y366668D01*
X121553Y366937D01*
X121708Y367167D01*
X121915Y367358D01*
G01X121812Y368848D02*
X121553Y369117D01*
X121450Y369423D01*
X121553Y369730D01*
X121863Y369998D01*
X122328Y370190D01*
X122793Y370267D01*
X123362D01*
X123827Y370190D01*
X124240Y369998D01*
X124447Y369768D01*
X124550Y369500D01*
X124447Y369193D01*
X124240Y368963D01*
X123930Y368810D01*
X123517Y368733D01*
X123155Y368810D01*
X122793Y369002D01*
X122587Y369232D01*
X122535Y369500D01*
X122638Y369807D01*
X122897Y370037D01*
X123362Y370267D01*
G01X121812Y371948D02*
X121553Y372217D01*
X121450Y372523D01*
X121553Y372830D01*
X121863Y373098D01*
X122328Y373290D01*
X122793Y373367D01*
X123362D01*
X123827Y373290D01*
X124240Y373098D01*
X124447Y372868D01*
X124550Y372600D01*
X124447Y372293D01*
X124240Y372063D01*
X123930Y371910D01*
X123517Y371833D01*
X123155Y371910D01*
X122793Y372102D01*
X122587Y372332D01*
X122535Y372600D01*
X122638Y372907D01*
X122897Y373137D01*
X123362Y373367D01*
G01X133550Y366133D02*
X130450D01*
Y367667D01*
G01X133033Y369272D02*
X133343Y369502D01*
X133498Y369770D01*
X133550Y370077D01*
X133447Y370460D01*
X133188Y370728D01*
X132878Y370805D01*
X132568Y370767D01*
X132310Y370613D01*
X131793Y369847D01*
X131432Y369502D01*
X130915Y369272D01*
X130450Y369195D01*
Y370805D01*
G01X133033Y372372D02*
X133343Y372602D01*
X133498Y372870D01*
X133550Y373177D01*
X133447Y373560D01*
X133188Y373828D01*
X132878Y373905D01*
X132568Y373867D01*
X132310Y373713D01*
X131793Y372947D01*
X131432Y372602D01*
X130915Y372372D01*
X130450Y372295D01*
Y373905D01*
G01X133617Y386250D02*
Y389350D01*
X132658D01*
X132352Y389195D01*
X132160Y388988D01*
X132083Y388575D01*
X132160Y388162D01*
X132390Y387903D01*
X132658Y387748D01*
X133617D01*
G01X132658D02*
X132083Y386250D01*
G01X129750D02*
Y389350D01*
X130210Y388730D01*
G01Y386250D02*
X129290D01*
G01X126190D02*
Y389350D01*
X127608Y387128D01*
X125692D01*
G01X124278Y388833D02*
X124048Y389143D01*
X123780Y389298D01*
X123473Y389350D01*
X123090Y389247D01*
X122822Y388988D01*
X122745Y388678D01*
X122783Y388368D01*
X122937Y388110D01*
X123703Y387593D01*
X124048Y387232D01*
X124278Y386715D01*
X124355Y386250D01*
X122745D01*
G01X133567Y390650D02*
Y393750D01*
X132608D01*
X132302Y393595D01*
X132110Y393388D01*
X132033Y392975D01*
X132110Y392562D01*
X132340Y392303D01*
X132608Y392148D01*
X133567D01*
G01X132608D02*
X132033Y390650D01*
G01X129240D02*
Y393750D01*
X130658Y391528D01*
X128742D01*
G01X126600Y390650D02*
X126332Y390702D01*
X126025Y390857D01*
X125833Y391115D01*
X125757Y391477D01*
X125833Y391838D01*
X126063Y392148D01*
X126408Y392303D01*
X126792D01*
X127022Y392407D01*
X127213Y392665D01*
X127290Y393027D01*
X127175Y393388D01*
X126907Y393647D01*
X126600Y393750D01*
X126293Y393647D01*
X126025Y393388D01*
X125910Y393027D01*
X125987Y392665D01*
X126178Y392407D01*
X126408Y392303D01*
X126792D01*
X127137Y392148D01*
X127367Y391838D01*
X127443Y391477D01*
X127367Y391115D01*
X127175Y390857D01*
X126868Y390702D01*
X126600Y390650D01*
G01X133367Y380950D02*
Y384050D01*
X132408D01*
X132102Y383895D01*
X131910Y383688D01*
X131833Y383275D01*
X131910Y382862D01*
X132140Y382603D01*
X132408Y382448D01*
X133367D01*
G01X132408D02*
X131833Y380950D01*
G01X129040D02*
Y384050D01*
X130458Y381828D01*
X128542D01*
G01X126477Y380950D02*
X126400Y381622D01*
X126285Y382190D01*
X126132Y382707D01*
X125940Y383275D01*
X125633Y384050D01*
X127167D01*
G01X131957Y402492D02*
X132187Y402647D01*
X132455Y402750D01*
X132762D01*
X133107Y402595D01*
X133375Y402337D01*
X133567Y402027D01*
X133720Y401510D01*
X133758Y401045D01*
X133682Y400580D01*
X133567Y400270D01*
X133337Y399960D01*
X133068Y399753D01*
X132800Y399650D01*
X132532D01*
X132263Y399753D01*
X132033Y399908D01*
X131842Y400115D01*
G01X129240Y399650D02*
Y402750D01*
X130658Y400528D01*
X128742D01*
G01X127328Y402233D02*
X127098Y402543D01*
X126830Y402698D01*
X126523Y402750D01*
X126140Y402647D01*
X125872Y402388D01*
X125795Y402078D01*
X125833Y401768D01*
X125987Y401510D01*
X126753Y400993D01*
X127098Y400632D01*
X127328Y400115D01*
X127405Y399650D01*
X125795D01*
G01X133567Y395150D02*
Y398250D01*
X132608D01*
X132302Y398095D01*
X132110Y397888D01*
X132033Y397475D01*
X132110Y397062D01*
X132340Y396803D01*
X132608Y396648D01*
X133567D01*
G01X132608D02*
X132033Y395150D01*
G01X130543Y395770D02*
X130313Y395408D01*
X130007Y395202D01*
X129662Y395150D01*
X129355Y395202D01*
X129048Y395460D01*
X128857Y395770D01*
X128818Y396080D01*
X128895Y396442D01*
X129163Y396700D01*
X129432Y396803D01*
X129777D01*
G01X129432D02*
X129202Y396958D01*
X129010Y397217D01*
X128933Y397527D01*
X129010Y397837D01*
X129202Y398095D01*
X129547Y398250D01*
X129892Y398198D01*
X130237Y397992D01*
G01X126600Y398250D02*
X126907Y398147D01*
X127137Y397888D01*
X127290Y397578D01*
X127405Y397165D01*
X127443Y396700D01*
X127405Y396235D01*
X127290Y395822D01*
X127137Y395512D01*
X126907Y395253D01*
X126600Y395150D01*
X126293Y395253D01*
X126063Y395512D01*
X125910Y395822D01*
X125795Y396235D01*
X125757Y396700D01*
X125795Y397165D01*
X125910Y397578D01*
X126063Y397888D01*
X126293Y398147D01*
X126600Y398250D01*
G01X132367Y406950D02*
Y410050D01*
X131408D01*
X131102Y409895D01*
X130910Y409688D01*
X130833Y409275D01*
X130910Y408862D01*
X131140Y408603D01*
X131408Y408448D01*
X132367D01*
G01X131408D02*
X130833Y406950D01*
G01X129343Y407415D02*
X129113Y407157D01*
X128845Y407002D01*
X128500Y406950D01*
X128155Y407053D01*
X127887Y407260D01*
X127695Y407622D01*
X127657Y408035D01*
X127733Y408448D01*
X127925Y408707D01*
X128193Y408913D01*
X128462Y408965D01*
X128730Y408913D01*
X129075Y408707D01*
X128960Y410050D01*
X127925D01*
G01X125400D02*
X125707Y409947D01*
X125937Y409688D01*
X126090Y409378D01*
X126205Y408965D01*
X126243Y408500D01*
X126205Y408035D01*
X126090Y407622D01*
X125937Y407312D01*
X125707Y407053D01*
X125400Y406950D01*
X125093Y407053D01*
X124863Y407312D01*
X124710Y407622D01*
X124595Y408035D01*
X124557Y408500D01*
X124595Y408965D01*
X124710Y409378D01*
X124863Y409688D01*
X125093Y409947D01*
X125400Y410050D01*
G01X138367Y415500D02*
Y418600D01*
X137408D01*
X137102Y418445D01*
X136910Y418238D01*
X136833Y417825D01*
X136910Y417412D01*
X137140Y417153D01*
X137408Y416998D01*
X138367D01*
G01X137408D02*
X136833Y415500D01*
G01X135343Y416120D02*
X135113Y415758D01*
X134807Y415552D01*
X134462Y415500D01*
X134155Y415552D01*
X133848Y415810D01*
X133657Y416120D01*
X133618Y416430D01*
X133695Y416792D01*
X133963Y417050D01*
X134232Y417153D01*
X134577D01*
G01X134232D02*
X134002Y417308D01*
X133810Y417567D01*
X133733Y417877D01*
X133810Y418187D01*
X134002Y418445D01*
X134347Y418600D01*
X134692Y418548D01*
X135037Y418342D01*
G01X132128Y418083D02*
X131898Y418393D01*
X131630Y418548D01*
X131323Y418600D01*
X130940Y418497D01*
X130672Y418238D01*
X130595Y417928D01*
X130633Y417618D01*
X130787Y417360D01*
X131553Y416843D01*
X131898Y416482D01*
X132128Y415965D01*
X132205Y415500D01*
X130595D01*
G01X150917Y71450D02*
Y74550D01*
X149958D01*
X149652Y74395D01*
X149460Y74188D01*
X149383Y73775D01*
X149460Y73362D01*
X149690Y73103D01*
X149958Y72948D01*
X150917D01*
G01X149958D02*
X149383Y71450D01*
G01X147050D02*
Y74550D01*
X147510Y73930D01*
G01Y71450D02*
X146590D01*
G01X144793Y71915D02*
X144563Y71657D01*
X144295Y71502D01*
X143950Y71450D01*
X143605Y71553D01*
X143337Y71760D01*
X143145Y72122D01*
X143107Y72535D01*
X143183Y72948D01*
X143375Y73207D01*
X143643Y73413D01*
X143912Y73465D01*
X144180Y73413D01*
X144525Y73207D01*
X144410Y74550D01*
X143375D01*
G01X140850Y71450D02*
X140582Y71502D01*
X140275Y71657D01*
X140083Y71915D01*
X140007Y72277D01*
X140083Y72638D01*
X140313Y72948D01*
X140658Y73103D01*
X141042D01*
X141272Y73207D01*
X141463Y73465D01*
X141540Y73827D01*
X141425Y74188D01*
X141157Y74447D01*
X140850Y74550D01*
X140543Y74447D01*
X140275Y74188D01*
X140160Y73827D01*
X140237Y73465D01*
X140428Y73207D01*
X140658Y73103D01*
X141042D01*
X141387Y72948D01*
X141617Y72638D01*
X141693Y72277D01*
X141617Y71915D01*
X141425Y71657D01*
X141118Y71502D01*
X140850Y71450D01*
G01X150917Y64450D02*
Y67550D01*
X149958D01*
X149652Y67395D01*
X149460Y67188D01*
X149383Y66775D01*
X149460Y66362D01*
X149690Y66103D01*
X149958Y65948D01*
X150917D01*
G01X149958D02*
X149383Y64450D01*
G01X147050D02*
Y67550D01*
X147510Y66930D01*
G01Y64450D02*
X146590D01*
G01X144027D02*
X143950Y65122D01*
X143835Y65690D01*
X143682Y66207D01*
X143490Y66775D01*
X143183Y67550D01*
X144717D01*
G01X141578Y65742D02*
X141310Y66103D01*
X141080Y66310D01*
X140773Y66413D01*
X140505Y66310D01*
X140313Y66103D01*
X140160Y65793D01*
X140122Y65432D01*
X140160Y65122D01*
X140313Y64812D01*
X140543Y64553D01*
X140812Y64450D01*
X141118Y64553D01*
X141387Y64863D01*
X141540Y65328D01*
X141578Y65845D01*
X141502Y66517D01*
X141387Y66878D01*
X141195Y67240D01*
X140927Y67498D01*
X140658Y67550D01*
X140390Y67447D01*
X140198Y67188D01*
G01X153417Y302950D02*
Y306050D01*
X152458D01*
X152152Y305895D01*
X151960Y305688D01*
X151883Y305275D01*
X151960Y304862D01*
X152190Y304603D01*
X152458Y304448D01*
X153417D01*
G01X152458D02*
X151883Y302950D01*
G01X149090D02*
Y306050D01*
X150508Y303828D01*
X148592D01*
G01X147102Y303312D02*
X146833Y303053D01*
X146527Y302950D01*
X146220Y303053D01*
X145952Y303363D01*
X145760Y303828D01*
X145683Y304293D01*
Y304862D01*
X145760Y305327D01*
X145952Y305740D01*
X146182Y305947D01*
X146450Y306050D01*
X146757Y305947D01*
X146987Y305740D01*
X147140Y305430D01*
X147217Y305017D01*
X147140Y304655D01*
X146948Y304293D01*
X146718Y304087D01*
X146450Y304035D01*
X146143Y304138D01*
X145913Y304397D01*
X145683Y304862D01*
G01X143350Y302950D02*
Y306050D01*
X143810Y305430D01*
G01Y302950D02*
X142890D01*
G01X137792Y367743D02*
X137947Y367513D01*
X138050Y367245D01*
Y366938D01*
X137895Y366593D01*
X137637Y366325D01*
X137327Y366133D01*
X136810Y365980D01*
X136345Y365942D01*
X135880Y366018D01*
X135570Y366133D01*
X135260Y366363D01*
X135053Y366632D01*
X134950Y366900D01*
Y367168D01*
X135053Y367437D01*
X135208Y367667D01*
X135415Y367858D01*
G01X135312Y369348D02*
X135053Y369617D01*
X134950Y369923D01*
X135053Y370230D01*
X135363Y370498D01*
X135828Y370690D01*
X136293Y370767D01*
X136862D01*
X137327Y370690D01*
X137740Y370498D01*
X137947Y370268D01*
X138050Y370000D01*
X137947Y369693D01*
X137740Y369463D01*
X137430Y369310D01*
X137017Y369233D01*
X136655Y369310D01*
X136293Y369502D01*
X136087Y369732D01*
X136035Y370000D01*
X136138Y370307D01*
X136397Y370537D01*
X136862Y370767D01*
G01X134950Y373100D02*
X138050D01*
X137430Y372640D01*
G01X134950D02*
Y373560D01*
G01X164292Y340743D02*
X164447Y340513D01*
X164550Y340245D01*
Y339938D01*
X164395Y339593D01*
X164137Y339325D01*
X163827Y339133D01*
X163310Y338980D01*
X162845Y338942D01*
X162380Y339018D01*
X162070Y339133D01*
X161760Y339363D01*
X161553Y339632D01*
X161450Y339900D01*
Y340168D01*
X161553Y340437D01*
X161708Y340667D01*
X161915Y340858D01*
G01X161450Y343000D02*
X161502Y343268D01*
X161657Y343575D01*
X161915Y343767D01*
X162277Y343843D01*
X162638Y343767D01*
X162948Y343537D01*
X163103Y343192D01*
Y342808D01*
X163207Y342578D01*
X163465Y342387D01*
X163827Y342310D01*
X164188Y342425D01*
X164447Y342693D01*
X164550Y343000D01*
X164447Y343307D01*
X164188Y343575D01*
X163827Y343690D01*
X163465Y343613D01*
X163207Y343422D01*
X163103Y343192D01*
Y342808D01*
X162948Y342463D01*
X162638Y342233D01*
X162277Y342157D01*
X161915Y342233D01*
X161657Y342425D01*
X161502Y342732D01*
X161450Y343000D01*
G01Y346100D02*
X161502Y346368D01*
X161657Y346675D01*
X161915Y346867D01*
X162277Y346943D01*
X162638Y346867D01*
X162948Y346637D01*
X163103Y346292D01*
Y345908D01*
X163207Y345678D01*
X163465Y345487D01*
X163827Y345410D01*
X164188Y345525D01*
X164447Y345793D01*
X164550Y346100D01*
X164447Y346407D01*
X164188Y346675D01*
X163827Y346790D01*
X163465Y346713D01*
X163207Y346522D01*
X163103Y346292D01*
Y345908D01*
X162948Y345563D01*
X162638Y345333D01*
X162277Y345257D01*
X161915Y345333D01*
X161657Y345525D01*
X161502Y345832D01*
X161450Y346100D01*
G01X161867Y371450D02*
Y374550D01*
X160908D01*
X160602Y374395D01*
X160410Y374188D01*
X160333Y373775D01*
X160410Y373362D01*
X160640Y373103D01*
X160908Y372948D01*
X161867D01*
G01X160908D02*
X160333Y371450D01*
G01X157540D02*
Y374550D01*
X158958Y372328D01*
X157042D01*
G01X155552Y371812D02*
X155283Y371553D01*
X154977Y371450D01*
X154670Y371553D01*
X154402Y371863D01*
X154210Y372328D01*
X154133Y372793D01*
Y373362D01*
X154210Y373827D01*
X154402Y374240D01*
X154632Y374447D01*
X154900Y374550D01*
X155207Y374447D01*
X155437Y374240D01*
X155590Y373930D01*
X155667Y373517D01*
X155590Y373155D01*
X155398Y372793D01*
X155168Y372587D01*
X154900Y372535D01*
X154593Y372638D01*
X154363Y372897D01*
X154133Y373362D01*
G01X165367Y391950D02*
Y395050D01*
X164408D01*
X164102Y394895D01*
X163910Y394688D01*
X163833Y394275D01*
X163910Y393862D01*
X164140Y393603D01*
X164408Y393448D01*
X165367D01*
G01X164408D02*
X163833Y391950D01*
G01X162343Y392570D02*
X162113Y392208D01*
X161807Y392002D01*
X161462Y391950D01*
X161155Y392002D01*
X160848Y392260D01*
X160657Y392570D01*
X160618Y392880D01*
X160695Y393242D01*
X160963Y393500D01*
X161232Y393603D01*
X161577D01*
G01X161232D02*
X161002Y393758D01*
X160810Y394017D01*
X160733Y394327D01*
X160810Y394637D01*
X161002Y394895D01*
X161347Y395050D01*
X161692Y394998D01*
X162037Y394792D01*
G01X158400Y391950D02*
Y395050D01*
X158860Y394430D01*
G01Y391950D02*
X157940D01*
G01X167305Y397463D02*
X166998Y397205D01*
X166653Y397050D01*
X166347D01*
X166040Y397205D01*
X165810Y397463D01*
X165695Y397825D01*
X165772Y398187D01*
X165963Y398497D01*
X166308Y398703D01*
X166768Y398807D01*
X167037Y399013D01*
X167152Y399375D01*
X167075Y399737D01*
X166883Y399995D01*
X166615Y400150D01*
X166347D01*
X166078Y400047D01*
X165848Y399788D01*
G01X164167Y397050D02*
Y400150D01*
X163247D01*
X162940Y399995D01*
X162710Y399633D01*
X162633Y399220D01*
X162710Y398807D01*
X162902Y398497D01*
X163247Y398342D01*
X164167D01*
G01X160300Y397050D02*
Y400150D01*
X160760Y399530D01*
G01Y397050D02*
X159840D01*
G01X188008Y36450D02*
X187050Y39550D01*
X186092Y36450D01*
G01X186437Y37535D02*
X187663D01*
G01X183950Y36450D02*
Y39550D01*
X184410Y38930D01*
G01Y36450D02*
X183490D01*
G01X184950Y68133D02*
X188050D01*
Y69092D01*
X187895Y69398D01*
X187688Y69590D01*
X187275Y69667D01*
X186862Y69590D01*
X186603Y69360D01*
X186448Y69092D01*
Y68133D01*
G01Y69092D02*
X184950Y69667D01*
G01X187533Y71272D02*
X187843Y71502D01*
X187998Y71770D01*
X188050Y72077D01*
X187947Y72460D01*
X187688Y72728D01*
X187378Y72805D01*
X187068Y72767D01*
X186810Y72613D01*
X186293Y71847D01*
X185932Y71502D01*
X185415Y71272D01*
X184950Y71195D01*
Y72805D01*
G01X185570Y74257D02*
X185208Y74487D01*
X185002Y74793D01*
X184950Y75138D01*
X185002Y75445D01*
X185260Y75752D01*
X185570Y75943D01*
X185880Y75982D01*
X186242Y75905D01*
X186500Y75637D01*
X186603Y75368D01*
Y75023D01*
G01Y75368D02*
X186758Y75598D01*
X187017Y75790D01*
X187327Y75867D01*
X187637Y75790D01*
X187895Y75598D01*
X188050Y75253D01*
X187998Y74908D01*
X187792Y74563D01*
G01X169343Y333915D02*
X169113Y333657D01*
X168845Y333502D01*
X168500Y333450D01*
X168155Y333553D01*
X167887Y333760D01*
X167695Y334122D01*
X167657Y334535D01*
X167733Y334948D01*
X167925Y335207D01*
X168193Y335413D01*
X168462Y335465D01*
X168730Y335413D01*
X169075Y335207D01*
X168960Y336550D01*
X167925D01*
G01X168500Y352950D02*
X168232Y353002D01*
X167925Y353157D01*
X167733Y353415D01*
X167657Y353777D01*
X167733Y354138D01*
X167963Y354448D01*
X168308Y354603D01*
X168692D01*
X168922Y354707D01*
X169113Y354965D01*
X169190Y355327D01*
X169075Y355688D01*
X168807Y355947D01*
X168500Y356050D01*
X168193Y355947D01*
X167925Y355688D01*
X167810Y355327D01*
X167887Y354965D01*
X168078Y354707D01*
X168308Y354603D01*
X168692D01*
X169037Y354448D01*
X169267Y354138D01*
X169343Y353777D01*
X169267Y353415D01*
X169075Y353157D01*
X168768Y353002D01*
X168500Y352950D01*
G01X190943Y362550D02*
Y360328D01*
X190790Y359863D01*
X190483Y359553D01*
X190100Y359450D01*
X189717Y359553D01*
X189410Y359863D01*
X189257Y360328D01*
Y362550D01*
G01X187843Y360070D02*
X187613Y359708D01*
X187307Y359502D01*
X186962Y359450D01*
X186655Y359502D01*
X186348Y359760D01*
X186157Y360070D01*
X186118Y360380D01*
X186195Y360742D01*
X186463Y361000D01*
X186732Y361103D01*
X187077D01*
G01X186732D02*
X186502Y361258D01*
X186310Y361517D01*
X186233Y361827D01*
X186310Y362137D01*
X186502Y362395D01*
X186847Y362550D01*
X187192Y362498D01*
X187537Y362292D01*
G01X183900Y359450D02*
Y362550D01*
X184360Y361930D01*
G01Y359450D02*
X183440D01*
G01X186357Y392292D02*
X186587Y392447D01*
X186855Y392550D01*
X187162D01*
X187507Y392395D01*
X187775Y392137D01*
X187967Y391827D01*
X188120Y391310D01*
X188158Y390845D01*
X188082Y390380D01*
X187967Y390070D01*
X187737Y389760D01*
X187468Y389553D01*
X187200Y389450D01*
X186932D01*
X186663Y389553D01*
X186433Y389708D01*
X186242Y389915D01*
G01X183640Y389450D02*
Y392550D01*
X185058Y390328D01*
X183142D01*
G01X180540Y389450D02*
Y392550D01*
X181958Y390328D01*
X180042D01*
G01X186892Y401643D02*
X187047Y401413D01*
X187150Y401145D01*
Y400838D01*
X186995Y400493D01*
X186737Y400225D01*
X186427Y400033D01*
X185910Y399880D01*
X185445Y399842D01*
X184980Y399918D01*
X184670Y400033D01*
X184360Y400263D01*
X184153Y400532D01*
X184050Y400800D01*
Y401068D01*
X184153Y401337D01*
X184308Y401567D01*
X184515Y401758D01*
G01X184050Y404360D02*
X187150D01*
X184928Y402942D01*
Y404858D01*
G01X184515Y406157D02*
X184257Y406387D01*
X184102Y406655D01*
X184050Y407000D01*
X184153Y407345D01*
X184360Y407613D01*
X184722Y407805D01*
X185135Y407843D01*
X185548Y407767D01*
X185807Y407575D01*
X186013Y407307D01*
X186065Y407038D01*
X186013Y406770D01*
X185807Y406425D01*
X187150Y406540D01*
Y407575D01*
G01X187167Y417950D02*
Y421050D01*
X186208D01*
X185902Y420895D01*
X185710Y420688D01*
X185633Y420275D01*
X185710Y419862D01*
X185940Y419603D01*
X186208Y419448D01*
X187167D01*
G01X186208D02*
X185633Y417950D01*
G01X184143Y418570D02*
X183913Y418208D01*
X183607Y418002D01*
X183262Y417950D01*
X182955Y418002D01*
X182648Y418260D01*
X182457Y418570D01*
X182418Y418880D01*
X182495Y419242D01*
X182763Y419500D01*
X183032Y419603D01*
X183377D01*
G01X183032D02*
X182802Y419758D01*
X182610Y420017D01*
X182533Y420327D01*
X182610Y420637D01*
X182802Y420895D01*
X183147Y421050D01*
X183492Y420998D01*
X183837Y420792D01*
G01X181043Y418570D02*
X180813Y418208D01*
X180507Y418002D01*
X180162Y417950D01*
X179855Y418002D01*
X179548Y418260D01*
X179357Y418570D01*
X179318Y418880D01*
X179395Y419242D01*
X179663Y419500D01*
X179932Y419603D01*
X180277D01*
G01X179932D02*
X179702Y419758D01*
X179510Y420017D01*
X179433Y420327D01*
X179510Y420637D01*
X179702Y420895D01*
X180047Y421050D01*
X180392Y420998D01*
X180737Y420792D01*
G01X191950Y289083D02*
X195050D01*
Y290042D01*
X194895Y290348D01*
X194688Y290540D01*
X194275Y290617D01*
X193862Y290540D01*
X193603Y290310D01*
X193448Y290042D01*
Y289083D01*
G01Y290042D02*
X191950Y290617D01*
G01Y293410D02*
X195050D01*
X192828Y291992D01*
Y293908D01*
G01X191950Y296050D02*
X192002Y296318D01*
X192157Y296625D01*
X192415Y296817D01*
X192777Y296893D01*
X193138Y296817D01*
X193448Y296587D01*
X193603Y296242D01*
Y295858D01*
X193707Y295628D01*
X193965Y295437D01*
X194327Y295360D01*
X194688Y295475D01*
X194947Y295743D01*
X195050Y296050D01*
X194947Y296357D01*
X194688Y296625D01*
X194327Y296740D01*
X193965Y296663D01*
X193707Y296472D01*
X193603Y296242D01*
Y295858D01*
X193448Y295513D01*
X193138Y295283D01*
X192777Y295207D01*
X192415Y295283D01*
X192157Y295475D01*
X192002Y295782D01*
X191950Y296050D01*
G01Y299150D02*
X192002Y299418D01*
X192157Y299725D01*
X192415Y299917D01*
X192777Y299993D01*
X193138Y299917D01*
X193448Y299687D01*
X193603Y299342D01*
Y298958D01*
X193707Y298728D01*
X193965Y298537D01*
X194327Y298460D01*
X194688Y298575D01*
X194947Y298843D01*
X195050Y299150D01*
X194947Y299457D01*
X194688Y299725D01*
X194327Y299840D01*
X193965Y299763D01*
X193707Y299572D01*
X193603Y299342D01*
Y298958D01*
X193448Y298613D01*
X193138Y298383D01*
X192777Y298307D01*
X192415Y298383D01*
X192157Y298575D01*
X192002Y298882D01*
X191950Y299150D01*
G01X219792Y75693D02*
X219947Y75463D01*
X220050Y75195D01*
Y74888D01*
X219895Y74543D01*
X219637Y74275D01*
X219327Y74083D01*
X218810Y73930D01*
X218345Y73892D01*
X217880Y73968D01*
X217570Y74083D01*
X217260Y74313D01*
X217053Y74582D01*
X216950Y74850D01*
Y75118D01*
X217053Y75387D01*
X217208Y75617D01*
X217415Y75808D01*
G01X219533Y77222D02*
X219843Y77452D01*
X219998Y77720D01*
X220050Y78027D01*
X219947Y78410D01*
X219688Y78678D01*
X219378Y78755D01*
X219068Y78717D01*
X218810Y78563D01*
X218293Y77797D01*
X217932Y77452D01*
X217415Y77222D01*
X216950Y77145D01*
Y78755D01*
G01Y81050D02*
X217002Y81318D01*
X217157Y81625D01*
X217415Y81817D01*
X217777Y81893D01*
X218138Y81817D01*
X218448Y81587D01*
X218603Y81242D01*
Y80858D01*
X218707Y80628D01*
X218965Y80437D01*
X219327Y80360D01*
X219688Y80475D01*
X219947Y80743D01*
X220050Y81050D01*
X219947Y81357D01*
X219688Y81625D01*
X219327Y81740D01*
X218965Y81663D01*
X218707Y81472D01*
X218603Y81242D01*
Y80858D01*
X218448Y80513D01*
X218138Y80283D01*
X217777Y80207D01*
X217415Y80283D01*
X217157Y80475D01*
X217002Y80782D01*
X216950Y81050D01*
G01X217312Y83498D02*
X217053Y83767D01*
X216950Y84073D01*
X217053Y84380D01*
X217363Y84648D01*
X217828Y84840D01*
X218293Y84917D01*
X218862D01*
X219327Y84840D01*
X219740Y84648D01*
X219947Y84418D01*
X220050Y84150D01*
X219947Y83843D01*
X219740Y83613D01*
X219430Y83460D01*
X219017Y83383D01*
X218655Y83460D01*
X218293Y83652D01*
X218087Y83882D01*
X218035Y84150D01*
X218138Y84457D01*
X218397Y84687D01*
X218862Y84917D01*
G01X293500Y141000D02*
Y180500D01*
X214500D01*
Y125500D01*
X238000D01*
Y131000D01*
X293500D01*
Y141000D01*
G01X216250Y305783D02*
X219350D01*
Y306742D01*
X219195Y307048D01*
X218988Y307240D01*
X218575Y307317D01*
X218162Y307240D01*
X217903Y307010D01*
X217748Y306742D01*
Y305783D01*
G01Y306742D02*
X216250Y307317D01*
G01Y310110D02*
X219350D01*
X217128Y308692D01*
Y310608D01*
G01X216250Y312750D02*
X219350D01*
X218730Y312290D01*
G01X216250D02*
Y313210D01*
G01X217542Y315122D02*
X217903Y315390D01*
X218110Y315620D01*
X218213Y315927D01*
X218110Y316195D01*
X217903Y316387D01*
X217593Y316540D01*
X217232Y316578D01*
X216922Y316540D01*
X216612Y316387D01*
X216353Y316157D01*
X216250Y315888D01*
X216353Y315582D01*
X216663Y315313D01*
X217128Y315160D01*
X217645Y315122D01*
X218317Y315198D01*
X218678Y315313D01*
X219040Y315505D01*
X219298Y315773D01*
X219350Y316042D01*
X219247Y316310D01*
X218988Y316502D01*
G01X211750Y305783D02*
X214850D01*
Y306742D01*
X214695Y307048D01*
X214488Y307240D01*
X214075Y307317D01*
X213662Y307240D01*
X213403Y307010D01*
X213248Y306742D01*
Y305783D01*
G01Y306742D02*
X211750Y307317D01*
G01Y310110D02*
X214850D01*
X212628Y308692D01*
Y310608D01*
G01X211750Y312750D02*
X214850D01*
X214230Y312290D01*
G01X211750D02*
Y313210D01*
G01X212370Y315007D02*
X212008Y315237D01*
X211802Y315543D01*
X211750Y315888D01*
X211802Y316195D01*
X212060Y316502D01*
X212370Y316693D01*
X212680Y316732D01*
X213042Y316655D01*
X213300Y316387D01*
X213403Y316118D01*
Y315773D01*
G01Y316118D02*
X213558Y316348D01*
X213817Y316540D01*
X214127Y316617D01*
X214437Y316540D01*
X214695Y316348D01*
X214850Y316003D01*
X214798Y315658D01*
X214592Y315313D01*
G01X207250Y305783D02*
X210350D01*
Y306742D01*
X210195Y307048D01*
X209988Y307240D01*
X209575Y307317D01*
X209162Y307240D01*
X208903Y307010D01*
X208748Y306742D01*
Y305783D01*
G01Y306742D02*
X207250Y307317D01*
G01Y310110D02*
X210350D01*
X208128Y308692D01*
Y310608D01*
G01X210350Y312750D02*
X210247Y312443D01*
X209988Y312213D01*
X209678Y312060D01*
X209265Y311945D01*
X208800Y311907D01*
X208335Y311945D01*
X207922Y312060D01*
X207612Y312213D01*
X207353Y312443D01*
X207250Y312750D01*
X207353Y313057D01*
X207612Y313287D01*
X207922Y313440D01*
X208335Y313555D01*
X208800Y313593D01*
X209265Y313555D01*
X209678Y313440D01*
X209988Y313287D01*
X210247Y313057D01*
X210350Y312750D01*
G01X207612Y315198D02*
X207353Y315467D01*
X207250Y315773D01*
X207353Y316080D01*
X207663Y316348D01*
X208128Y316540D01*
X208593Y316617D01*
X209162D01*
X209627Y316540D01*
X210040Y316348D01*
X210247Y316118D01*
X210350Y315850D01*
X210247Y315543D01*
X210040Y315313D01*
X209730Y315160D01*
X209317Y315083D01*
X208955Y315160D01*
X208593Y315352D01*
X208387Y315582D01*
X208335Y315850D01*
X208438Y316157D01*
X208697Y316387D01*
X209162Y316617D01*
G01X203040Y333950D02*
Y337050D01*
X204458Y334828D01*
X202542D01*
G01X218417Y361950D02*
Y365050D01*
X217458D01*
X217152Y364895D01*
X216960Y364688D01*
X216883Y364275D01*
X216960Y363862D01*
X217190Y363603D01*
X217458Y363448D01*
X218417D01*
G01X217458D02*
X216883Y361950D01*
G01X214090D02*
Y365050D01*
X215508Y362828D01*
X213592D01*
G01X212293Y362415D02*
X212063Y362157D01*
X211795Y362002D01*
X211450Y361950D01*
X211105Y362053D01*
X210837Y362260D01*
X210645Y362622D01*
X210607Y363035D01*
X210683Y363448D01*
X210875Y363707D01*
X211143Y363913D01*
X211412Y363965D01*
X211680Y363913D01*
X212025Y363707D01*
X211910Y365050D01*
X210875D01*
G01X207890Y361950D02*
Y365050D01*
X209308Y362828D01*
X207392D01*
G01X218417Y357950D02*
Y361050D01*
X217458D01*
X217152Y360895D01*
X216960Y360688D01*
X216883Y360275D01*
X216960Y359862D01*
X217190Y359603D01*
X217458Y359448D01*
X218417D01*
G01X217458D02*
X216883Y357950D01*
G01X214090D02*
Y361050D01*
X215508Y358828D01*
X213592D01*
G01X210990Y357950D02*
Y361050D01*
X212408Y358828D01*
X210492D01*
G01X207890Y357950D02*
Y361050D01*
X209308Y358828D01*
X207392D01*
G01X218417Y369950D02*
Y373050D01*
X217458D01*
X217152Y372895D01*
X216960Y372688D01*
X216883Y372275D01*
X216960Y371862D01*
X217190Y371603D01*
X217458Y371448D01*
X218417D01*
G01X217458D02*
X216883Y369950D01*
G01X214090D02*
Y373050D01*
X215508Y370828D01*
X213592D01*
G01X210990Y369950D02*
Y373050D01*
X212408Y370828D01*
X210492D01*
G01X209078Y371242D02*
X208810Y371603D01*
X208580Y371810D01*
X208273Y371913D01*
X208005Y371810D01*
X207813Y371603D01*
X207660Y371293D01*
X207622Y370932D01*
X207660Y370622D01*
X207813Y370312D01*
X208043Y370053D01*
X208312Y369950D01*
X208618Y370053D01*
X208887Y370363D01*
X209040Y370828D01*
X209078Y371345D01*
X209002Y372017D01*
X208887Y372378D01*
X208695Y372740D01*
X208427Y372998D01*
X208158Y373050D01*
X207890Y372947D01*
X207698Y372688D01*
G01X218417Y365950D02*
Y369050D01*
X217458D01*
X217152Y368895D01*
X216960Y368688D01*
X216883Y368275D01*
X216960Y367862D01*
X217190Y367603D01*
X217458Y367448D01*
X218417D01*
G01X217458D02*
X216883Y365950D01*
G01X214090D02*
Y369050D01*
X215508Y366828D01*
X213592D01*
G01X210990Y365950D02*
Y369050D01*
X212408Y366828D01*
X210492D01*
G01X208427Y365950D02*
X208350Y366622D01*
X208235Y367190D01*
X208082Y367707D01*
X207890Y368275D01*
X207583Y369050D01*
X209117D01*
G01X223792Y75693D02*
X223947Y75463D01*
X224050Y75195D01*
Y74888D01*
X223895Y74543D01*
X223637Y74275D01*
X223327Y74083D01*
X222810Y73930D01*
X222345Y73892D01*
X221880Y73968D01*
X221570Y74083D01*
X221260Y74313D01*
X221053Y74582D01*
X220950Y74850D01*
Y75118D01*
X221053Y75387D01*
X221208Y75617D01*
X221415Y75808D01*
G01X223533Y77222D02*
X223843Y77452D01*
X223998Y77720D01*
X224050Y78027D01*
X223947Y78410D01*
X223688Y78678D01*
X223378Y78755D01*
X223068Y78717D01*
X222810Y78563D01*
X222293Y77797D01*
X221932Y77452D01*
X221415Y77222D01*
X220950Y77145D01*
Y78755D01*
G01X221312Y80398D02*
X221053Y80667D01*
X220950Y80973D01*
X221053Y81280D01*
X221363Y81548D01*
X221828Y81740D01*
X222293Y81817D01*
X222862D01*
X223327Y81740D01*
X223740Y81548D01*
X223947Y81318D01*
X224050Y81050D01*
X223947Y80743D01*
X223740Y80513D01*
X223430Y80360D01*
X223017Y80283D01*
X222655Y80360D01*
X222293Y80552D01*
X222087Y80782D01*
X222035Y81050D01*
X222138Y81357D01*
X222397Y81587D01*
X222862Y81817D01*
G01X224050Y84150D02*
X223947Y83843D01*
X223688Y83613D01*
X223378Y83460D01*
X222965Y83345D01*
X222500Y83307D01*
X222035Y83345D01*
X221622Y83460D01*
X221312Y83613D01*
X221053Y83843D01*
X220950Y84150D01*
X221053Y84457D01*
X221312Y84687D01*
X221622Y84840D01*
X222035Y84955D01*
X222500Y84993D01*
X222965Y84955D01*
X223378Y84840D01*
X223688Y84687D01*
X223947Y84457D01*
X224050Y84150D01*
G01X235292Y67743D02*
X235447Y67513D01*
X235550Y67245D01*
Y66938D01*
X235395Y66593D01*
X235137Y66325D01*
X234827Y66133D01*
X234310Y65980D01*
X233845Y65942D01*
X233380Y66018D01*
X233070Y66133D01*
X232760Y66363D01*
X232553Y66632D01*
X232450Y66900D01*
Y67168D01*
X232553Y67437D01*
X232708Y67667D01*
X232915Y67858D01*
G01X232450Y70000D02*
X235550D01*
X234930Y69540D01*
G01X232450D02*
Y70460D01*
G01X232812Y72448D02*
X232553Y72717D01*
X232450Y73023D01*
X232553Y73330D01*
X232863Y73598D01*
X233328Y73790D01*
X233793Y73867D01*
X234362D01*
X234827Y73790D01*
X235240Y73598D01*
X235447Y73368D01*
X235550Y73100D01*
X235447Y72793D01*
X235240Y72563D01*
X234930Y72410D01*
X234517Y72333D01*
X234155Y72410D01*
X233793Y72602D01*
X233587Y72832D01*
X233535Y73100D01*
X233638Y73407D01*
X233897Y73637D01*
X234362Y73867D01*
G01X228050Y77633D02*
X224950D01*
Y79167D01*
G01X227533Y80772D02*
X227843Y81002D01*
X227998Y81270D01*
X228050Y81577D01*
X227947Y81960D01*
X227688Y82228D01*
X227378Y82305D01*
X227068Y82267D01*
X226810Y82113D01*
X226293Y81347D01*
X225932Y81002D01*
X225415Y80772D01*
X224950Y80695D01*
Y82305D01*
G01Y84600D02*
X228050D01*
X227430Y84140D01*
G01X224950D02*
Y85060D01*
G01X234542Y129787D02*
X234667Y129627D01*
X234750Y129440D01*
Y129227D01*
X234625Y128987D01*
X234417Y128800D01*
X234167Y128667D01*
X233750Y128560D01*
X233375Y128533D01*
X233000Y128587D01*
X232750Y128667D01*
X232500Y128827D01*
X232333Y129013D01*
X232250Y129200D01*
Y129387D01*
X232333Y129573D01*
X232458Y129733D01*
X232625Y129867D01*
G01X234333Y130893D02*
X234583Y131053D01*
X234708Y131240D01*
X234750Y131453D01*
X234667Y131720D01*
X234458Y131907D01*
X234208Y131960D01*
X233958Y131933D01*
X233750Y131827D01*
X233333Y131293D01*
X233042Y131053D01*
X232625Y130893D01*
X232250Y130840D01*
Y131960D01*
G01Y133600D02*
X234750D01*
X234250Y133280D01*
G01X232250D02*
Y133920D01*
G01X232750Y135213D02*
X232458Y135373D01*
X232292Y135587D01*
X232250Y135827D01*
X232292Y136040D01*
X232500Y136253D01*
X232750Y136387D01*
X233000Y136413D01*
X233292Y136360D01*
X233500Y136173D01*
X233583Y135987D01*
Y135747D01*
G01Y135987D02*
X233708Y136147D01*
X233917Y136280D01*
X234167Y136333D01*
X234417Y136280D01*
X234625Y136147D01*
X234750Y135907D01*
X234708Y135667D01*
X234542Y135427D01*
G01X232772Y138227D02*
X232897Y138067D01*
X232980Y137880D01*
Y137667D01*
X232855Y137427D01*
X232647Y137240D01*
X232397Y137107D01*
X231980Y137000D01*
X231605Y136973D01*
X231230Y137027D01*
X230980Y137107D01*
X230730Y137267D01*
X230563Y137453D01*
X230480Y137640D01*
Y137827D01*
X230563Y138013D01*
X230688Y138173D01*
X230855Y138307D01*
G01X232563Y139333D02*
X232813Y139493D01*
X232938Y139680D01*
X232980Y139893D01*
X232897Y140160D01*
X232688Y140347D01*
X232438Y140400D01*
X232188Y140373D01*
X231980Y140267D01*
X231563Y139733D01*
X231272Y139493D01*
X230855Y139333D01*
X230480Y139280D01*
Y140400D01*
G01Y142040D02*
X232980D01*
X232480Y141720D01*
G01X230480D02*
Y142360D01*
G01Y144187D02*
X231022Y144240D01*
X231480Y144320D01*
X231897Y144427D01*
X232355Y144560D01*
X232980Y144773D01*
Y143707D01*
G01X227713Y141542D02*
X227873Y141667D01*
X228060Y141750D01*
X228273D01*
X228513Y141625D01*
X228700Y141417D01*
X228833Y141167D01*
X228940Y140750D01*
X228967Y140375D01*
X228913Y140000D01*
X228833Y139750D01*
X228673Y139500D01*
X228487Y139333D01*
X228300Y139250D01*
X228113D01*
X227927Y139333D01*
X227767Y139458D01*
X227633Y139625D01*
G01X226100Y139250D02*
Y141750D01*
X226420Y141250D01*
G01Y139250D02*
X225780D01*
G01X223900D02*
Y141750D01*
X224220Y141250D01*
G01Y139250D02*
X223580D01*
G01X221700Y141750D02*
X221913Y141667D01*
X222073Y141458D01*
X222180Y141208D01*
X222260Y140875D01*
X222287Y140500D01*
X222260Y140125D01*
X222180Y139792D01*
X222073Y139542D01*
X221913Y139333D01*
X221700Y139250D01*
X221487Y139333D01*
X221327Y139542D01*
X221220Y139792D01*
X221140Y140125D01*
X221113Y140500D01*
X221140Y140875D01*
X221220Y141208D01*
X221327Y141458D01*
X221487Y141667D01*
X221700Y141750D01*
G01X236712Y138227D02*
X236837Y138067D01*
X236920Y137880D01*
Y137667D01*
X236795Y137427D01*
X236587Y137240D01*
X236337Y137107D01*
X235920Y137000D01*
X235545Y136973D01*
X235170Y137027D01*
X234920Y137107D01*
X234670Y137267D01*
X234503Y137453D01*
X234420Y137640D01*
Y137827D01*
X234503Y138013D01*
X234628Y138173D01*
X234795Y138307D01*
G01X234420Y139840D02*
X236920D01*
X236420Y139520D01*
G01X234420D02*
Y140160D01*
G01X236503Y141533D02*
X236753Y141693D01*
X236878Y141880D01*
X236920Y142093D01*
X236837Y142360D01*
X236628Y142547D01*
X236378Y142600D01*
X236128Y142573D01*
X235920Y142467D01*
X235503Y141933D01*
X235212Y141693D01*
X234795Y141533D01*
X234420Y141480D01*
Y142600D01*
G01Y144560D02*
X236920D01*
X235128Y143573D01*
Y144907D01*
G01X236712Y147107D02*
X236837Y146947D01*
X236920Y146760D01*
Y146547D01*
X236795Y146307D01*
X236587Y146120D01*
X236337Y145987D01*
X235920Y145880D01*
X235545Y145853D01*
X235170Y145907D01*
X234920Y145987D01*
X234670Y146147D01*
X234503Y146333D01*
X234420Y146520D01*
Y146707D01*
X234503Y146893D01*
X234628Y147053D01*
X234795Y147187D01*
G01X236503Y148213D02*
X236753Y148373D01*
X236878Y148560D01*
X236920Y148773D01*
X236837Y149040D01*
X236628Y149227D01*
X236378Y149280D01*
X236128Y149253D01*
X235920Y149147D01*
X235503Y148613D01*
X235212Y148373D01*
X234795Y148213D01*
X234420Y148160D01*
Y149280D01*
G01Y150920D02*
X236920D01*
X236420Y150600D01*
G01X234420D02*
Y151240D01*
G01Y153120D02*
X234462Y153307D01*
X234587Y153520D01*
X234795Y153653D01*
X235087Y153707D01*
X235378Y153653D01*
X235628Y153493D01*
X235753Y153253D01*
Y152987D01*
X235837Y152827D01*
X236045Y152693D01*
X236337Y152640D01*
X236628Y152720D01*
X236837Y152907D01*
X236920Y153120D01*
X236837Y153333D01*
X236628Y153520D01*
X236337Y153600D01*
X236045Y153547D01*
X235837Y153413D01*
X235753Y153253D01*
Y152987D01*
X235628Y152747D01*
X235378Y152587D01*
X235087Y152533D01*
X234795Y152587D01*
X234587Y152720D01*
X234462Y152933D01*
X234420Y153120D01*
G01X230213Y150042D02*
X230373Y150167D01*
X230560Y150250D01*
X230773D01*
X231013Y150125D01*
X231200Y149917D01*
X231333Y149667D01*
X231440Y149250D01*
X231467Y148875D01*
X231413Y148500D01*
X231333Y148250D01*
X231173Y148000D01*
X230987Y147833D01*
X230800Y147750D01*
X230613D01*
X230427Y147833D01*
X230267Y147958D01*
X230133Y148125D01*
G01X228600Y147750D02*
Y150250D01*
X228920Y149750D01*
G01Y147750D02*
X228280D01*
G01X226400D02*
Y150250D01*
X226720Y149750D01*
G01Y147750D02*
X226080D01*
G01X224253D02*
X224200Y148292D01*
X224120Y148750D01*
X224013Y149167D01*
X223880Y149625D01*
X223667Y150250D01*
X224733D01*
G01X236542Y156287D02*
X236667Y156127D01*
X236750Y155940D01*
Y155727D01*
X236625Y155487D01*
X236417Y155300D01*
X236167Y155167D01*
X235750Y155060D01*
X235375Y155033D01*
X235000Y155087D01*
X234750Y155167D01*
X234500Y155327D01*
X234333Y155513D01*
X234250Y155700D01*
Y155887D01*
X234333Y156073D01*
X234458Y156233D01*
X234625Y156367D01*
G01X234250Y157900D02*
X236750D01*
X236250Y157580D01*
G01X234250D02*
Y158220D01*
G01X234750Y159513D02*
X234458Y159673D01*
X234292Y159887D01*
X234250Y160127D01*
X234292Y160340D01*
X234500Y160553D01*
X234750Y160687D01*
X235000Y160713D01*
X235292Y160660D01*
X235500Y160473D01*
X235583Y160287D01*
Y160047D01*
G01Y160287D02*
X235708Y160447D01*
X235917Y160580D01*
X236167Y160633D01*
X236417Y160580D01*
X236625Y160447D01*
X236750Y160207D01*
X236708Y159967D01*
X236542Y159727D01*
G01X234250Y162300D02*
X236750D01*
X236250Y161980D01*
G01X234250D02*
Y162620D01*
G01X230713Y161042D02*
X230873Y161167D01*
X231060Y161250D01*
X231273D01*
X231513Y161125D01*
X231700Y160917D01*
X231833Y160667D01*
X231940Y160250D01*
X231967Y159875D01*
X231913Y159500D01*
X231833Y159250D01*
X231673Y159000D01*
X231487Y158833D01*
X231300Y158750D01*
X231113D01*
X230927Y158833D01*
X230767Y158958D01*
X230633Y159125D01*
G01X229607Y160833D02*
X229447Y161083D01*
X229260Y161208D01*
X229047Y161250D01*
X228780Y161167D01*
X228593Y160958D01*
X228540Y160708D01*
X228567Y160458D01*
X228673Y160250D01*
X229207Y159833D01*
X229447Y159542D01*
X229607Y159125D01*
X229660Y158750D01*
X228540D01*
G01X226900Y161250D02*
X227113Y161167D01*
X227273Y160958D01*
X227380Y160708D01*
X227460Y160375D01*
X227487Y160000D01*
X227460Y159625D01*
X227380Y159292D01*
X227273Y159042D01*
X227113Y158833D01*
X226900Y158750D01*
X226687Y158833D01*
X226527Y159042D01*
X226420Y159292D01*
X226340Y159625D01*
X226313Y160000D01*
X226340Y160375D01*
X226420Y160708D01*
X226527Y160958D01*
X226687Y161167D01*
X226900Y161250D01*
G01X225153Y159042D02*
X224967Y158833D01*
X224753Y158750D01*
X224540Y158833D01*
X224353Y159083D01*
X224220Y159458D01*
X224167Y159833D01*
Y160292D01*
X224220Y160667D01*
X224353Y161000D01*
X224513Y161167D01*
X224700Y161250D01*
X224913Y161167D01*
X225073Y161000D01*
X225180Y160750D01*
X225233Y160417D01*
X225180Y160125D01*
X225047Y159833D01*
X224887Y159667D01*
X224700Y159625D01*
X224487Y159708D01*
X224327Y159917D01*
X224167Y160292D01*
G01X237050Y218557D02*
X234828D01*
X234363Y218710D01*
X234053Y219017D01*
X233950Y219400D01*
X234053Y219783D01*
X234363Y220090D01*
X234828Y220243D01*
X237050D01*
G01X233950Y222500D02*
X237050D01*
X236430Y222040D01*
G01X233950D02*
Y222960D01*
G01X237050Y225600D02*
X236947Y225293D01*
X236688Y225063D01*
X236378Y224910D01*
X235965Y224795D01*
X235500Y224757D01*
X235035Y224795D01*
X234622Y224910D01*
X234312Y225063D01*
X234053Y225293D01*
X233950Y225600D01*
X234053Y225907D01*
X234312Y226137D01*
X234622Y226290D01*
X235035Y226405D01*
X235500Y226443D01*
X235965Y226405D01*
X236378Y226290D01*
X236688Y226137D01*
X236947Y225907D01*
X237050Y225600D01*
G01X236680Y228450D02*
Y230950D01*
X237667Y229158D01*
X236333D01*
G01X236257Y236792D02*
X236487Y236947D01*
X236755Y237050D01*
X237062D01*
X237407Y236895D01*
X237675Y236637D01*
X237867Y236327D01*
X238020Y235810D01*
X238058Y235345D01*
X237982Y234880D01*
X237867Y234570D01*
X237637Y234260D01*
X237368Y234053D01*
X237100Y233950D01*
X236832D01*
X236563Y234053D01*
X236333Y234208D01*
X236142Y234415D01*
G01X234728Y235242D02*
X234460Y235603D01*
X234230Y235810D01*
X233923Y235913D01*
X233655Y235810D01*
X233463Y235603D01*
X233310Y235293D01*
X233272Y234932D01*
X233310Y234622D01*
X233463Y234312D01*
X233693Y234053D01*
X233962Y233950D01*
X234268Y234053D01*
X234537Y234363D01*
X234690Y234828D01*
X234728Y235345D01*
X234652Y236017D01*
X234537Y236378D01*
X234345Y236740D01*
X234077Y236998D01*
X233808Y237050D01*
X233540Y236947D01*
X233348Y236688D01*
G01X230900Y233950D02*
X230632Y234002D01*
X230325Y234157D01*
X230133Y234415D01*
X230057Y234777D01*
X230133Y235138D01*
X230363Y235448D01*
X230708Y235603D01*
X231092D01*
X231322Y235707D01*
X231513Y235965D01*
X231590Y236327D01*
X231475Y236688D01*
X231207Y236947D01*
X230900Y237050D01*
X230593Y236947D01*
X230325Y236688D01*
X230210Y236327D01*
X230287Y235965D01*
X230478Y235707D01*
X230708Y235603D01*
X231092D01*
X231437Y235448D01*
X231667Y235138D01*
X231743Y234777D01*
X231667Y234415D01*
X231475Y234157D01*
X231168Y234002D01*
X230900Y233950D01*
G01X240992Y49043D02*
X241147Y48813D01*
X241250Y48545D01*
Y48238D01*
X241095Y47893D01*
X240837Y47625D01*
X240527Y47433D01*
X240010Y47280D01*
X239545Y47242D01*
X239080Y47318D01*
X238770Y47433D01*
X238460Y47663D01*
X238253Y47932D01*
X238150Y48200D01*
Y48468D01*
X238253Y48737D01*
X238408Y48967D01*
X238615Y49158D01*
G01X240733Y50572D02*
X241043Y50802D01*
X241198Y51070D01*
X241250Y51377D01*
X241147Y51760D01*
X240888Y52028D01*
X240578Y52105D01*
X240268Y52067D01*
X240010Y51913D01*
X239493Y51147D01*
X239132Y50802D01*
X238615Y50572D01*
X238150Y50495D01*
Y52105D01*
G01X238770Y53557D02*
X238408Y53787D01*
X238202Y54093D01*
X238150Y54438D01*
X238202Y54745D01*
X238460Y55052D01*
X238770Y55243D01*
X239080Y55282D01*
X239442Y55205D01*
X239700Y54937D01*
X239803Y54668D01*
Y54323D01*
G01Y54668D02*
X239958Y54898D01*
X240217Y55090D01*
X240527Y55167D01*
X240837Y55090D01*
X241095Y54898D01*
X241250Y54553D01*
X241198Y54208D01*
X240992Y53863D01*
G01X247042Y50887D02*
X247167Y50727D01*
X247250Y50540D01*
Y50327D01*
X247125Y50087D01*
X246917Y49900D01*
X246667Y49767D01*
X246250Y49660D01*
X245875Y49633D01*
X245500Y49687D01*
X245250Y49767D01*
X245000Y49927D01*
X244833Y50113D01*
X244750Y50300D01*
Y50487D01*
X244833Y50673D01*
X244958Y50833D01*
X245125Y50967D01*
G01X246833Y51993D02*
X247083Y52153D01*
X247208Y52340D01*
X247250Y52553D01*
X247167Y52820D01*
X246958Y53007D01*
X246708Y53060D01*
X246458Y53033D01*
X246250Y52927D01*
X245833Y52393D01*
X245542Y52153D01*
X245125Y51993D01*
X244750Y51940D01*
Y53060D01*
G01Y55020D02*
X247250D01*
X245458Y54033D01*
Y55367D01*
G01X253042Y50887D02*
X253167Y50727D01*
X253250Y50540D01*
Y50327D01*
X253125Y50087D01*
X252917Y49900D01*
X252667Y49767D01*
X252250Y49660D01*
X251875Y49633D01*
X251500Y49687D01*
X251250Y49767D01*
X251000Y49927D01*
X250833Y50113D01*
X250750Y50300D01*
Y50487D01*
X250833Y50673D01*
X250958Y50833D01*
X251125Y50967D01*
G01X252833Y51993D02*
X253083Y52153D01*
X253208Y52340D01*
X253250Y52553D01*
X253167Y52820D01*
X252958Y53007D01*
X252708Y53060D01*
X252458Y53033D01*
X252250Y52927D01*
X251833Y52393D01*
X251542Y52153D01*
X251125Y51993D01*
X250750Y51940D01*
Y53060D01*
G01X251125Y54113D02*
X250917Y54273D01*
X250792Y54460D01*
X250750Y54700D01*
X250833Y54940D01*
X251000Y55127D01*
X251292Y55260D01*
X251625Y55287D01*
X251958Y55233D01*
X252167Y55100D01*
X252333Y54913D01*
X252375Y54727D01*
X252333Y54540D01*
X252167Y54300D01*
X253250Y54380D01*
Y55100D01*
G01X253463Y144652D02*
X253623Y144777D01*
X253810Y144860D01*
X254023D01*
X254263Y144735D01*
X254450Y144527D01*
X254583Y144277D01*
X254690Y143860D01*
X254717Y143485D01*
X254663Y143110D01*
X254583Y142860D01*
X254423Y142610D01*
X254237Y142443D01*
X254050Y142360D01*
X253863D01*
X253677Y142443D01*
X253517Y142568D01*
X253383Y142735D01*
G01X251850Y142360D02*
Y144860D01*
X252170Y144360D01*
G01Y142360D02*
X251530D01*
G01X249330D02*
Y144860D01*
X250317Y143068D01*
X248983D01*
G01X247957Y143402D02*
X247770Y143693D01*
X247610Y143860D01*
X247397Y143943D01*
X247210Y143860D01*
X247077Y143693D01*
X246970Y143443D01*
X246943Y143152D01*
X246970Y142902D01*
X247077Y142652D01*
X247237Y142443D01*
X247423Y142360D01*
X247637Y142443D01*
X247823Y142693D01*
X247930Y143068D01*
X247957Y143485D01*
X247903Y144027D01*
X247823Y144318D01*
X247690Y144610D01*
X247503Y144818D01*
X247317Y144860D01*
X247130Y144777D01*
X246997Y144568D01*
G01X253463Y148592D02*
X253623Y148717D01*
X253810Y148800D01*
X254023D01*
X254263Y148675D01*
X254450Y148467D01*
X254583Y148217D01*
X254690Y147800D01*
X254717Y147425D01*
X254663Y147050D01*
X254583Y146800D01*
X254423Y146550D01*
X254237Y146383D01*
X254050Y146300D01*
X253863D01*
X253677Y146383D01*
X253517Y146508D01*
X253383Y146675D01*
G01X252357Y148383D02*
X252197Y148633D01*
X252010Y148758D01*
X251797Y148800D01*
X251530Y148717D01*
X251343Y148508D01*
X251290Y148258D01*
X251317Y148008D01*
X251423Y147800D01*
X251957Y147383D01*
X252197Y147092D01*
X252357Y146675D01*
X252410Y146300D01*
X251290D01*
G01X249650Y148800D02*
X249863Y148717D01*
X250023Y148508D01*
X250130Y148258D01*
X250210Y147925D01*
X250237Y147550D01*
X250210Y147175D01*
X250130Y146842D01*
X250023Y146592D01*
X249863Y146383D01*
X249650Y146300D01*
X249437Y146383D01*
X249277Y146592D01*
X249170Y146842D01*
X249090Y147175D01*
X249063Y147550D01*
X249090Y147925D01*
X249170Y148258D01*
X249277Y148508D01*
X249437Y148717D01*
X249650Y148800D01*
G01X247130Y146300D02*
Y148800D01*
X248117Y147008D01*
X246783D01*
G01X245833Y142250D02*
Y144750D01*
X245167D01*
X244953Y144625D01*
X244820Y144458D01*
X244767Y144125D01*
X244820Y143792D01*
X244980Y143583D01*
X245167Y143458D01*
X245833D01*
G01X245167D02*
X244767Y142250D01*
G01X243100D02*
Y144750D01*
X243420Y144250D01*
G01Y142250D02*
X242780D01*
G01X241353Y142542D02*
X241167Y142333D01*
X240953Y142250D01*
X240740Y142333D01*
X240553Y142583D01*
X240420Y142958D01*
X240367Y143333D01*
Y143792D01*
X240420Y144167D01*
X240553Y144500D01*
X240713Y144667D01*
X240900Y144750D01*
X241113Y144667D01*
X241273Y144500D01*
X241380Y144250D01*
X241433Y143917D01*
X241380Y143625D01*
X241247Y143333D01*
X241087Y143167D01*
X240900Y143125D01*
X240687Y143208D01*
X240527Y143417D01*
X240367Y143792D01*
G01X238753Y142250D02*
X238700Y142792D01*
X238620Y143250D01*
X238513Y143667D01*
X238380Y144125D01*
X238167Y144750D01*
X239233D01*
G01X254962Y159917D02*
X255087Y159757D01*
X255170Y159570D01*
Y159357D01*
X255045Y159117D01*
X254837Y158930D01*
X254587Y158797D01*
X254170Y158690D01*
X253795Y158663D01*
X253420Y158717D01*
X253170Y158797D01*
X252920Y158957D01*
X252753Y159143D01*
X252670Y159330D01*
Y159517D01*
X252753Y159703D01*
X252878Y159863D01*
X253045Y159997D01*
G01X252670Y161530D02*
X255170D01*
X254670Y161210D01*
G01X252670D02*
Y161850D01*
G01X253045Y163143D02*
X252837Y163303D01*
X252712Y163490D01*
X252670Y163730D01*
X252753Y163970D01*
X252920Y164157D01*
X253212Y164290D01*
X253545Y164317D01*
X253878Y164263D01*
X254087Y164130D01*
X254253Y163943D01*
X254295Y163757D01*
X254253Y163570D01*
X254087Y163330D01*
X255170Y163410D01*
Y164130D01*
G01X253712Y165423D02*
X254003Y165610D01*
X254170Y165770D01*
X254253Y165983D01*
X254170Y166170D01*
X254003Y166303D01*
X253753Y166410D01*
X253462Y166437D01*
X253212Y166410D01*
X252962Y166303D01*
X252753Y166143D01*
X252670Y165957D01*
X252753Y165743D01*
X253003Y165557D01*
X253378Y165450D01*
X253795Y165423D01*
X254337Y165477D01*
X254628Y165557D01*
X254920Y165690D01*
X255128Y165877D01*
X255170Y166063D01*
X255087Y166250D01*
X254878Y166383D01*
G01X254962Y151537D02*
X255087Y151377D01*
X255170Y151190D01*
Y150977D01*
X255045Y150737D01*
X254837Y150550D01*
X254587Y150417D01*
X254170Y150310D01*
X253795Y150283D01*
X253420Y150337D01*
X253170Y150417D01*
X252920Y150577D01*
X252753Y150763D01*
X252670Y150950D01*
Y151137D01*
X252753Y151323D01*
X252878Y151483D01*
X253045Y151617D01*
G01X252670Y153150D02*
X255170D01*
X254670Y152830D01*
G01X252670D02*
Y153470D01*
G01X254753Y154843D02*
X255003Y155003D01*
X255128Y155190D01*
X255170Y155403D01*
X255087Y155670D01*
X254878Y155857D01*
X254628Y155910D01*
X254378Y155883D01*
X254170Y155777D01*
X253753Y155243D01*
X253462Y155003D01*
X253045Y154843D01*
X252670Y154790D01*
Y155910D01*
G01Y157550D02*
X255170D01*
X254670Y157230D01*
G01X252670D02*
Y157870D01*
G01X250522Y159417D02*
X250647Y159257D01*
X250730Y159070D01*
Y158857D01*
X250605Y158617D01*
X250397Y158430D01*
X250147Y158297D01*
X249730Y158190D01*
X249355Y158163D01*
X248980Y158217D01*
X248730Y158297D01*
X248480Y158457D01*
X248313Y158643D01*
X248230Y158830D01*
Y159017D01*
X248313Y159203D01*
X248438Y159363D01*
X248605Y159497D01*
G01X250313Y160523D02*
X250563Y160683D01*
X250688Y160870D01*
X250730Y161083D01*
X250647Y161350D01*
X250438Y161537D01*
X250188Y161590D01*
X249938Y161563D01*
X249730Y161457D01*
X249313Y160923D01*
X249022Y160683D01*
X248605Y160523D01*
X248230Y160470D01*
Y161590D01*
G01X250313Y162723D02*
X250563Y162883D01*
X250688Y163070D01*
X250730Y163283D01*
X250647Y163550D01*
X250438Y163737D01*
X250188Y163790D01*
X249938Y163763D01*
X249730Y163657D01*
X249313Y163123D01*
X249022Y162883D01*
X248605Y162723D01*
X248230Y162670D01*
Y163790D01*
G01X250313Y164923D02*
X250563Y165083D01*
X250688Y165270D01*
X250730Y165483D01*
X250647Y165750D01*
X250438Y165937D01*
X250188Y165990D01*
X249938Y165963D01*
X249730Y165857D01*
X249313Y165323D01*
X249022Y165083D01*
X248605Y164923D01*
X248230Y164870D01*
Y165990D01*
G01X250533Y156962D02*
X250693Y157087D01*
X250880Y157170D01*
X251093D01*
X251333Y157045D01*
X251520Y156837D01*
X251653Y156587D01*
X251760Y156170D01*
X251787Y155795D01*
X251733Y155420D01*
X251653Y155170D01*
X251493Y154920D01*
X251307Y154753D01*
X251120Y154670D01*
X250933D01*
X250747Y154753D01*
X250587Y154878D01*
X250453Y155045D01*
G01X248920Y154670D02*
Y157170D01*
X249240Y156670D01*
G01Y154670D02*
X248600D01*
G01X246720D02*
Y157170D01*
X247040Y156670D01*
G01Y154670D02*
X246400D01*
G01X244520D02*
Y157170D01*
X244840Y156670D01*
G01Y154670D02*
X244200D01*
G01X242652Y155977D02*
X242777Y155817D01*
X242860Y155630D01*
Y155417D01*
X242735Y155177D01*
X242527Y154990D01*
X242277Y154857D01*
X241860Y154750D01*
X241485Y154723D01*
X241110Y154777D01*
X240860Y154857D01*
X240610Y155017D01*
X240443Y155203D01*
X240360Y155390D01*
Y155577D01*
X240443Y155763D01*
X240568Y155923D01*
X240735Y156057D01*
G01X240360Y157590D02*
X242860D01*
X242360Y157270D01*
G01X240360D02*
Y157910D01*
G01X242860Y159790D02*
X242777Y159577D01*
X242568Y159417D01*
X242318Y159310D01*
X241985Y159230D01*
X241610Y159203D01*
X241235Y159230D01*
X240902Y159310D01*
X240652Y159417D01*
X240443Y159577D01*
X240360Y159790D01*
X240443Y160003D01*
X240652Y160163D01*
X240902Y160270D01*
X241235Y160350D01*
X241610Y160377D01*
X241985Y160350D01*
X242318Y160270D01*
X242568Y160163D01*
X242777Y160003D01*
X242860Y159790D01*
G01X240735Y161403D02*
X240527Y161563D01*
X240402Y161750D01*
X240360Y161990D01*
X240443Y162230D01*
X240610Y162417D01*
X240902Y162550D01*
X241235Y162577D01*
X241568Y162523D01*
X241777Y162390D01*
X241943Y162203D01*
X241985Y162017D01*
X241943Y161830D01*
X241777Y161590D01*
X242860Y161670D01*
Y162390D01*
G01X250533Y153022D02*
X250693Y153147D01*
X250880Y153230D01*
X251093D01*
X251333Y153105D01*
X251520Y152897D01*
X251653Y152647D01*
X251760Y152230D01*
X251787Y151855D01*
X251733Y151480D01*
X251653Y151230D01*
X251493Y150980D01*
X251307Y150813D01*
X251120Y150730D01*
X250933D01*
X250747Y150813D01*
X250587Y150938D01*
X250453Y151105D01*
G01X248920Y150730D02*
Y153230D01*
X249240Y152730D01*
G01Y150730D02*
X248600D01*
G01X246720D02*
Y153230D01*
X247040Y152730D01*
G01Y150730D02*
X246400D01*
G01X244520D02*
X244333Y150772D01*
X244120Y150897D01*
X243987Y151105D01*
X243933Y151397D01*
X243987Y151688D01*
X244147Y151938D01*
X244387Y152063D01*
X244653D01*
X244813Y152147D01*
X244947Y152355D01*
X245000Y152647D01*
X244920Y152938D01*
X244733Y153147D01*
X244520Y153230D01*
X244307Y153147D01*
X244120Y152938D01*
X244040Y152647D01*
X244093Y152355D01*
X244227Y152147D01*
X244387Y152063D01*
X244653D01*
X244893Y151938D01*
X245053Y151688D01*
X245107Y151397D01*
X245053Y151105D01*
X244920Y150897D01*
X244707Y150772D01*
X244520Y150730D01*
G01X246833Y163750D02*
Y166250D01*
X246167D01*
X245953Y166125D01*
X245820Y165958D01*
X245767Y165625D01*
X245820Y165292D01*
X245980Y165083D01*
X246167Y164958D01*
X246833D01*
G01X246167D02*
X245767Y163750D01*
G01X244100D02*
Y166250D01*
X244420Y165750D01*
G01Y163750D02*
X243780D01*
G01X242353Y164042D02*
X242167Y163833D01*
X241953Y163750D01*
X241740Y163833D01*
X241553Y164083D01*
X241420Y164458D01*
X241367Y164833D01*
Y165292D01*
X241420Y165667D01*
X241553Y166000D01*
X241713Y166167D01*
X241900Y166250D01*
X242113Y166167D01*
X242273Y166000D01*
X242380Y165750D01*
X242433Y165417D01*
X242380Y165125D01*
X242247Y164833D01*
X242087Y164667D01*
X241900Y164625D01*
X241687Y164708D01*
X241527Y164917D01*
X241367Y165292D01*
G01X239700Y163750D02*
X239513Y163792D01*
X239300Y163917D01*
X239167Y164125D01*
X239113Y164417D01*
X239167Y164708D01*
X239327Y164958D01*
X239567Y165083D01*
X239833D01*
X239993Y165167D01*
X240127Y165375D01*
X240180Y165667D01*
X240100Y165958D01*
X239913Y166167D01*
X239700Y166250D01*
X239487Y166167D01*
X239300Y165958D01*
X239220Y165667D01*
X239273Y165375D01*
X239407Y165167D01*
X239567Y165083D01*
X239833D01*
X240073Y164958D01*
X240233Y164708D01*
X240287Y164417D01*
X240233Y164125D01*
X240100Y163917D01*
X239887Y163792D01*
X239700Y163750D01*
G01X244113Y169742D02*
X244273Y169867D01*
X244460Y169950D01*
X244673D01*
X244913Y169825D01*
X245100Y169617D01*
X245233Y169367D01*
X245340Y168950D01*
X245367Y168575D01*
X245313Y168200D01*
X245233Y167950D01*
X245073Y167700D01*
X244887Y167533D01*
X244700Y167450D01*
X244513D01*
X244327Y167533D01*
X244167Y167658D01*
X244033Y167825D01*
G01X242500Y167450D02*
Y169950D01*
X242820Y169450D01*
G01Y167450D02*
X242180D01*
G01X240300D02*
Y169950D01*
X240620Y169450D01*
G01Y167450D02*
X239980D01*
G01X238687Y167950D02*
X238527Y167658D01*
X238313Y167492D01*
X238073Y167450D01*
X237860Y167492D01*
X237647Y167700D01*
X237513Y167950D01*
X237487Y168200D01*
X237540Y168492D01*
X237727Y168700D01*
X237913Y168783D01*
X238153D01*
G01X237913D02*
X237753Y168908D01*
X237620Y169117D01*
X237567Y169367D01*
X237620Y169617D01*
X237753Y169825D01*
X237993Y169950D01*
X238233Y169908D01*
X238473Y169742D01*
G01X254213D02*
X254373Y169867D01*
X254560Y169950D01*
X254773D01*
X255013Y169825D01*
X255200Y169617D01*
X255333Y169367D01*
X255440Y168950D01*
X255467Y168575D01*
X255413Y168200D01*
X255333Y167950D01*
X255173Y167700D01*
X254987Y167533D01*
X254800Y167450D01*
X254613D01*
X254427Y167533D01*
X254267Y167658D01*
X254133Y167825D01*
G01X253107Y169533D02*
X252947Y169783D01*
X252760Y169908D01*
X252547Y169950D01*
X252280Y169867D01*
X252093Y169658D01*
X252040Y169408D01*
X252067Y169158D01*
X252173Y168950D01*
X252707Y168533D01*
X252947Y168242D01*
X253107Y167825D01*
X253160Y167450D01*
X252040D01*
G01X250400D02*
Y169950D01*
X250720Y169450D01*
G01Y167450D02*
X250080D01*
G01X248653Y167742D02*
X248467Y167533D01*
X248253Y167450D01*
X248040Y167533D01*
X247853Y167783D01*
X247720Y168158D01*
X247667Y168533D01*
Y168992D01*
X247720Y169367D01*
X247853Y169700D01*
X248013Y169867D01*
X248200Y169950D01*
X248413Y169867D01*
X248573Y169700D01*
X248680Y169450D01*
X248733Y169117D01*
X248680Y168825D01*
X248547Y168533D01*
X248387Y168367D01*
X248200Y168325D01*
X247987Y168408D01*
X247827Y168617D01*
X247667Y168992D01*
G01X253950Y190633D02*
X257050D01*
Y191592D01*
X256895Y191898D01*
X256688Y192090D01*
X256275Y192167D01*
X255862Y192090D01*
X255603Y191860D01*
X255448Y191592D01*
Y190633D01*
G01Y191592D02*
X253950Y192167D01*
G01X254312Y193848D02*
X254053Y194117D01*
X253950Y194423D01*
X254053Y194730D01*
X254363Y194998D01*
X254828Y195190D01*
X255293Y195267D01*
X255862D01*
X256327Y195190D01*
X256740Y194998D01*
X256947Y194768D01*
X257050Y194500D01*
X256947Y194193D01*
X256740Y193963D01*
X256430Y193810D01*
X256017Y193733D01*
X255655Y193810D01*
X255293Y194002D01*
X255087Y194232D01*
X255035Y194500D01*
X255138Y194807D01*
X255397Y195037D01*
X255862Y195267D01*
G01X254312Y196948D02*
X254053Y197217D01*
X253950Y197523D01*
X254053Y197830D01*
X254363Y198098D01*
X254828Y198290D01*
X255293Y198367D01*
X255862D01*
X256327Y198290D01*
X256740Y198098D01*
X256947Y197868D01*
X257050Y197600D01*
X256947Y197293D01*
X256740Y197063D01*
X256430Y196910D01*
X256017Y196833D01*
X255655Y196910D01*
X255293Y197102D01*
X255087Y197332D01*
X255035Y197600D01*
X255138Y197907D01*
X255397Y198137D01*
X255862Y198367D01*
G01X238587Y212950D02*
X238427Y212658D01*
X238213Y212492D01*
X237973Y212450D01*
X237760Y212492D01*
X237547Y212700D01*
X237413Y212950D01*
X237387Y213200D01*
X237440Y213492D01*
X237627Y213700D01*
X237813Y213783D01*
X238053D01*
G01X237813D02*
X237653Y213908D01*
X237520Y214117D01*
X237467Y214367D01*
X237520Y214617D01*
X237653Y214825D01*
X237893Y214950D01*
X238133Y214908D01*
X238373Y214742D01*
G01X253950Y199583D02*
X257050D01*
Y200542D01*
X256895Y200848D01*
X256688Y201040D01*
X256275Y201117D01*
X255862Y201040D01*
X255603Y200810D01*
X255448Y200542D01*
Y199583D01*
G01Y200542D02*
X253950Y201117D01*
G01Y203450D02*
X257050D01*
X256430Y202990D01*
G01X253950D02*
Y203910D01*
G01X257050Y206550D02*
X256947Y206243D01*
X256688Y206013D01*
X256378Y205860D01*
X255965Y205745D01*
X255500Y205707D01*
X255035Y205745D01*
X254622Y205860D01*
X254312Y206013D01*
X254053Y206243D01*
X253950Y206550D01*
X254053Y206857D01*
X254312Y207087D01*
X254622Y207240D01*
X255035Y207355D01*
X255500Y207393D01*
X255965Y207355D01*
X256378Y207240D01*
X256688Y207087D01*
X256947Y206857D01*
X257050Y206550D01*
G01Y209650D02*
X256947Y209343D01*
X256688Y209113D01*
X256378Y208960D01*
X255965Y208845D01*
X255500Y208807D01*
X255035Y208845D01*
X254622Y208960D01*
X254312Y209113D01*
X254053Y209343D01*
X253950Y209650D01*
X254053Y209957D01*
X254312Y210187D01*
X254622Y210340D01*
X255035Y210455D01*
X255500Y210493D01*
X255965Y210455D01*
X256378Y210340D01*
X256688Y210187D01*
X256947Y209957D01*
X257050Y209650D01*
G01X250587Y229325D02*
X250427Y229117D01*
X250240Y228992D01*
X250000Y228950D01*
X249760Y229033D01*
X249573Y229200D01*
X249440Y229492D01*
X249413Y229825D01*
X249467Y230158D01*
X249600Y230367D01*
X249787Y230533D01*
X249973Y230575D01*
X250160Y230533D01*
X250400Y230367D01*
X250320Y231450D01*
X249600D01*
G01X249917Y240450D02*
Y243550D01*
X248958D01*
X248652Y243395D01*
X248460Y243188D01*
X248383Y242775D01*
X248460Y242362D01*
X248690Y242103D01*
X248958Y241948D01*
X249917D01*
G01X248958D02*
X248383Y240450D01*
G01X246050D02*
Y243550D01*
X246510Y242930D01*
G01Y240450D02*
X245590D01*
G01X242950Y243550D02*
X243257Y243447D01*
X243487Y243188D01*
X243640Y242878D01*
X243755Y242465D01*
X243793Y242000D01*
X243755Y241535D01*
X243640Y241122D01*
X243487Y240812D01*
X243257Y240553D01*
X242950Y240450D01*
X242643Y240553D01*
X242413Y240812D01*
X242260Y241122D01*
X242145Y241535D01*
X242107Y242000D01*
X242145Y242465D01*
X242260Y242878D01*
X242413Y243188D01*
X242643Y243447D01*
X242950Y243550D01*
G01X239927Y240450D02*
X239850Y241122D01*
X239735Y241690D01*
X239582Y242207D01*
X239390Y242775D01*
X239083Y243550D01*
X240617D01*
G01X262917Y240450D02*
Y243550D01*
X261958D01*
X261652Y243395D01*
X261460Y243188D01*
X261383Y242775D01*
X261460Y242362D01*
X261690Y242103D01*
X261958Y241948D01*
X262917D01*
G01X261958D02*
X261383Y240450D01*
G01X259778Y243033D02*
X259548Y243343D01*
X259280Y243498D01*
X258973Y243550D01*
X258590Y243447D01*
X258322Y243188D01*
X258245Y242878D01*
X258283Y242568D01*
X258437Y242310D01*
X259203Y241793D01*
X259548Y241432D01*
X259778Y240915D01*
X259855Y240450D01*
X258245D01*
G01X256678Y241742D02*
X256410Y242103D01*
X256180Y242310D01*
X255873Y242413D01*
X255605Y242310D01*
X255413Y242103D01*
X255260Y241793D01*
X255222Y241432D01*
X255260Y241122D01*
X255413Y240812D01*
X255643Y240553D01*
X255912Y240450D01*
X256218Y240553D01*
X256487Y240863D01*
X256640Y241328D01*
X256678Y241845D01*
X256602Y242517D01*
X256487Y242878D01*
X256295Y243240D01*
X256027Y243498D01*
X255758Y243550D01*
X255490Y243447D01*
X255298Y243188D01*
G01X252927Y240450D02*
X252850Y241122D01*
X252735Y241690D01*
X252582Y242207D01*
X252390Y242775D01*
X252083Y243550D01*
X253617D01*
G01X266042Y46887D02*
X266167Y46727D01*
X266250Y46540D01*
Y46327D01*
X266125Y46087D01*
X265917Y45900D01*
X265667Y45767D01*
X265250Y45660D01*
X264875Y45633D01*
X264500Y45687D01*
X264250Y45767D01*
X264000Y45927D01*
X263833Y46113D01*
X263750Y46300D01*
Y46487D01*
X263833Y46673D01*
X263958Y46833D01*
X264125Y46967D01*
G01X265833Y47993D02*
X266083Y48153D01*
X266208Y48340D01*
X266250Y48553D01*
X266167Y48820D01*
X265958Y49007D01*
X265708Y49060D01*
X265458Y49033D01*
X265250Y48927D01*
X264833Y48393D01*
X264542Y48153D01*
X264125Y47993D01*
X263750Y47940D01*
Y49060D01*
G01X264792Y50193D02*
X265083Y50380D01*
X265250Y50540D01*
X265333Y50753D01*
X265250Y50940D01*
X265083Y51073D01*
X264833Y51180D01*
X264542Y51207D01*
X264292Y51180D01*
X264042Y51073D01*
X263833Y50913D01*
X263750Y50727D01*
X263833Y50513D01*
X264083Y50327D01*
X264458Y50220D01*
X264875Y50193D01*
X265417Y50247D01*
X265708Y50327D01*
X266000Y50460D01*
X266208Y50647D01*
X266250Y50833D01*
X266167Y51020D01*
X265958Y51153D01*
G01X272542Y46887D02*
X272667Y46727D01*
X272750Y46540D01*
Y46327D01*
X272625Y46087D01*
X272417Y45900D01*
X272167Y45767D01*
X271750Y45660D01*
X271375Y45633D01*
X271000Y45687D01*
X270750Y45767D01*
X270500Y45927D01*
X270333Y46113D01*
X270250Y46300D01*
Y46487D01*
X270333Y46673D01*
X270458Y46833D01*
X270625Y46967D01*
G01X272333Y47993D02*
X272583Y48153D01*
X272708Y48340D01*
X272750Y48553D01*
X272667Y48820D01*
X272458Y49007D01*
X272208Y49060D01*
X271958Y49033D01*
X271750Y48927D01*
X271333Y48393D01*
X271042Y48153D01*
X270625Y47993D01*
X270250Y47940D01*
Y49060D01*
G01Y50647D02*
X270792Y50700D01*
X271250Y50780D01*
X271667Y50887D01*
X272125Y51020D01*
X272750Y51233D01*
Y50167D01*
G01X272042Y138787D02*
X272167Y138627D01*
X272250Y138440D01*
Y138227D01*
X272125Y137987D01*
X271917Y137800D01*
X271667Y137667D01*
X271250Y137560D01*
X270875Y137533D01*
X270500Y137587D01*
X270250Y137667D01*
X270000Y137827D01*
X269833Y138013D01*
X269750Y138200D01*
Y138387D01*
X269833Y138573D01*
X269958Y138733D01*
X270125Y138867D01*
G01X271833Y139893D02*
X272083Y140053D01*
X272208Y140240D01*
X272250Y140453D01*
X272167Y140720D01*
X271958Y140907D01*
X271708Y140960D01*
X271458Y140933D01*
X271250Y140827D01*
X270833Y140293D01*
X270542Y140053D01*
X270125Y139893D01*
X269750Y139840D01*
Y140960D01*
G01X271833Y142093D02*
X272083Y142253D01*
X272208Y142440D01*
X272250Y142653D01*
X272167Y142920D01*
X271958Y143107D01*
X271708Y143160D01*
X271458Y143133D01*
X271250Y143027D01*
X270833Y142493D01*
X270542Y142253D01*
X270125Y142093D01*
X269750Y142040D01*
Y143160D01*
G01X272250Y144800D02*
X272167Y144587D01*
X271958Y144427D01*
X271708Y144320D01*
X271375Y144240D01*
X271000Y144213D01*
X270625Y144240D01*
X270292Y144320D01*
X270042Y144427D01*
X269833Y144587D01*
X269750Y144800D01*
X269833Y145013D01*
X270042Y145173D01*
X270292Y145280D01*
X270625Y145360D01*
X271000Y145387D01*
X271375Y145360D01*
X271708Y145280D01*
X271958Y145173D01*
X272167Y145013D01*
X272250Y144800D01*
G01X272152Y147607D02*
X272277Y147447D01*
X272360Y147260D01*
Y147047D01*
X272235Y146807D01*
X272027Y146620D01*
X271777Y146487D01*
X271360Y146380D01*
X270985Y146353D01*
X270610Y146407D01*
X270360Y146487D01*
X270110Y146647D01*
X269943Y146833D01*
X269860Y147020D01*
Y147207D01*
X269943Y147393D01*
X270068Y147553D01*
X270235Y147687D01*
G01X271943Y148713D02*
X272193Y148873D01*
X272318Y149060D01*
X272360Y149273D01*
X272277Y149540D01*
X272068Y149727D01*
X271818Y149780D01*
X271568Y149753D01*
X271360Y149647D01*
X270943Y149113D01*
X270652Y148873D01*
X270235Y148713D01*
X269860Y148660D01*
Y149780D01*
G01Y151420D02*
X272360D01*
X271860Y151100D01*
G01X269860D02*
Y151740D01*
G01Y153940D02*
X272360D01*
X270568Y152953D01*
Y154287D01*
G01X267642Y138787D02*
X267767Y138627D01*
X267850Y138440D01*
Y138227D01*
X267725Y137987D01*
X267517Y137800D01*
X267267Y137667D01*
X266850Y137560D01*
X266475Y137533D01*
X266100Y137587D01*
X265850Y137667D01*
X265600Y137827D01*
X265433Y138013D01*
X265350Y138200D01*
Y138387D01*
X265433Y138573D01*
X265558Y138733D01*
X265725Y138867D01*
G01X265350Y140400D02*
X267850D01*
X267350Y140080D01*
G01X265350D02*
Y140720D01*
G01Y142920D02*
X267850D01*
X266058Y141933D01*
Y143267D01*
G01X267433Y144293D02*
X267683Y144453D01*
X267808Y144640D01*
X267850Y144853D01*
X267767Y145120D01*
X267558Y145307D01*
X267308Y145360D01*
X267058Y145333D01*
X266850Y145227D01*
X266433Y144693D01*
X266142Y144453D01*
X265725Y144293D01*
X265350Y144240D01*
Y145360D01*
G01X258042Y134287D02*
X258167Y134127D01*
X258250Y133940D01*
Y133727D01*
X258125Y133487D01*
X257917Y133300D01*
X257667Y133167D01*
X257250Y133060D01*
X256875Y133033D01*
X256500Y133087D01*
X256250Y133167D01*
X256000Y133327D01*
X255833Y133513D01*
X255750Y133700D01*
Y133887D01*
X255833Y134073D01*
X255958Y134233D01*
X256125Y134367D01*
G01X257833Y135393D02*
X258083Y135553D01*
X258208Y135740D01*
X258250Y135953D01*
X258167Y136220D01*
X257958Y136407D01*
X257708Y136460D01*
X257458Y136433D01*
X257250Y136327D01*
X256833Y135793D01*
X256542Y135553D01*
X256125Y135393D01*
X255750Y135340D01*
Y136460D01*
G01X258250Y138100D02*
X258167Y137887D01*
X257958Y137727D01*
X257708Y137620D01*
X257375Y137540D01*
X257000Y137513D01*
X256625Y137540D01*
X256292Y137620D01*
X256042Y137727D01*
X255833Y137887D01*
X255750Y138100D01*
X255833Y138313D01*
X256042Y138473D01*
X256292Y138580D01*
X256625Y138660D01*
X257000Y138687D01*
X257375Y138660D01*
X257708Y138580D01*
X257958Y138473D01*
X258167Y138313D01*
X258250Y138100D01*
G01X255750Y140300D02*
X255792Y140487D01*
X255917Y140700D01*
X256125Y140833D01*
X256417Y140887D01*
X256708Y140833D01*
X256958Y140673D01*
X257083Y140433D01*
Y140167D01*
X257167Y140007D01*
X257375Y139873D01*
X257667Y139820D01*
X257958Y139900D01*
X258167Y140087D01*
X258250Y140300D01*
X258167Y140513D01*
X257958Y140700D01*
X257667Y140780D01*
X257375Y140727D01*
X257167Y140593D01*
X257083Y140433D01*
Y140167D01*
X256958Y139927D01*
X256708Y139767D01*
X256417Y139713D01*
X256125Y139767D01*
X255917Y139900D01*
X255792Y140113D01*
X255750Y140300D01*
G01X258402Y143167D02*
X258527Y143007D01*
X258610Y142820D01*
Y142607D01*
X258485Y142367D01*
X258277Y142180D01*
X258027Y142047D01*
X257610Y141940D01*
X257235Y141913D01*
X256860Y141967D01*
X256610Y142047D01*
X256360Y142207D01*
X256193Y142393D01*
X256110Y142580D01*
Y142767D01*
X256193Y142953D01*
X256318Y143113D01*
X256485Y143247D01*
G01X256110Y144780D02*
X258610D01*
X258110Y144460D01*
G01X256110D02*
Y145100D01*
G01X257152Y146473D02*
X257443Y146660D01*
X257610Y146820D01*
X257693Y147033D01*
X257610Y147220D01*
X257443Y147353D01*
X257193Y147460D01*
X256902Y147487D01*
X256652Y147460D01*
X256402Y147353D01*
X256193Y147193D01*
X256110Y147007D01*
X256193Y146793D01*
X256443Y146607D01*
X256818Y146500D01*
X257235Y146473D01*
X257777Y146527D01*
X258068Y146607D01*
X258360Y146740D01*
X258568Y146927D01*
X258610Y147113D01*
X258527Y147300D01*
X258318Y147433D01*
G01X256402Y148727D02*
X256193Y148913D01*
X256110Y149127D01*
X256193Y149340D01*
X256443Y149527D01*
X256818Y149660D01*
X257193Y149713D01*
X257652D01*
X258027Y149660D01*
X258360Y149527D01*
X258527Y149367D01*
X258610Y149180D01*
X258527Y148967D01*
X258360Y148807D01*
X258110Y148700D01*
X257777Y148647D01*
X257485Y148700D01*
X257193Y148833D01*
X257027Y148993D01*
X256985Y149180D01*
X257068Y149393D01*
X257277Y149553D01*
X257652Y149713D01*
G01X268042Y156787D02*
X268167Y156627D01*
X268250Y156440D01*
Y156227D01*
X268125Y155987D01*
X267917Y155800D01*
X267667Y155667D01*
X267250Y155560D01*
X266875Y155533D01*
X266500Y155587D01*
X266250Y155667D01*
X266000Y155827D01*
X265833Y156013D01*
X265750Y156200D01*
Y156387D01*
X265833Y156573D01*
X265958Y156733D01*
X266125Y156867D01*
G01X265750Y158400D02*
X268250D01*
X267750Y158080D01*
G01X265750D02*
Y158720D01*
G01Y160600D02*
X268250D01*
X267750Y160280D01*
G01X265750D02*
Y160920D01*
G01Y163120D02*
X268250D01*
X266458Y162133D01*
Y163467D01*
G01X267742Y147787D02*
X267867Y147627D01*
X267950Y147440D01*
Y147227D01*
X267825Y146987D01*
X267617Y146800D01*
X267367Y146667D01*
X266950Y146560D01*
X266575Y146533D01*
X266200Y146587D01*
X265950Y146667D01*
X265700Y146827D01*
X265533Y147013D01*
X265450Y147200D01*
Y147387D01*
X265533Y147573D01*
X265658Y147733D01*
X265825Y147867D01*
G01X265450Y149400D02*
X267950D01*
X267450Y149080D01*
G01X265450D02*
Y149720D01*
G01X265950Y151013D02*
X265658Y151173D01*
X265492Y151387D01*
X265450Y151627D01*
X265492Y151840D01*
X265700Y152053D01*
X265950Y152187D01*
X266200Y152213D01*
X266492Y152160D01*
X266700Y151973D01*
X266783Y151787D01*
Y151547D01*
G01Y151787D02*
X266908Y151947D01*
X267117Y152080D01*
X267367Y152133D01*
X267617Y152080D01*
X267825Y151947D01*
X267950Y151707D01*
X267908Y151467D01*
X267742Y151227D01*
G01X265950Y153213D02*
X265658Y153373D01*
X265492Y153587D01*
X265450Y153827D01*
X265492Y154040D01*
X265700Y154253D01*
X265950Y154387D01*
X266200Y154413D01*
X266492Y154360D01*
X266700Y154173D01*
X266783Y153987D01*
Y153747D01*
G01Y153987D02*
X266908Y154147D01*
X267117Y154280D01*
X267367Y154333D01*
X267617Y154280D01*
X267825Y154147D01*
X267950Y153907D01*
X267908Y153667D01*
X267742Y153427D01*
G01X258902Y155977D02*
X259027Y155817D01*
X259110Y155630D01*
Y155417D01*
X258985Y155177D01*
X258777Y154990D01*
X258527Y154857D01*
X258110Y154750D01*
X257735Y154723D01*
X257360Y154777D01*
X257110Y154857D01*
X256860Y155017D01*
X256693Y155203D01*
X256610Y155390D01*
Y155577D01*
X256693Y155763D01*
X256818Y155923D01*
X256985Y156057D01*
G01X256610Y157590D02*
X259110D01*
X258610Y157270D01*
G01X256610D02*
Y157910D01*
G01X258693Y159283D02*
X258943Y159443D01*
X259068Y159630D01*
X259110Y159843D01*
X259027Y160110D01*
X258818Y160297D01*
X258568Y160350D01*
X258318Y160323D01*
X258110Y160217D01*
X257693Y159683D01*
X257402Y159443D01*
X256985Y159283D01*
X256610Y159230D01*
Y160350D01*
G01X259110Y161990D02*
X259027Y161777D01*
X258818Y161617D01*
X258568Y161510D01*
X258235Y161430D01*
X257860Y161403D01*
X257485Y161430D01*
X257152Y161510D01*
X256902Y161617D01*
X256693Y161777D01*
X256610Y161990D01*
X256693Y162203D01*
X256902Y162363D01*
X257152Y162470D01*
X257485Y162550D01*
X257860Y162577D01*
X258235Y162550D01*
X258568Y162470D01*
X258818Y162363D01*
X259027Y162203D01*
X259110Y161990D01*
G01X272042Y156787D02*
X272167Y156627D01*
X272250Y156440D01*
Y156227D01*
X272125Y155987D01*
X271917Y155800D01*
X271667Y155667D01*
X271250Y155560D01*
X270875Y155533D01*
X270500Y155587D01*
X270250Y155667D01*
X270000Y155827D01*
X269833Y156013D01*
X269750Y156200D01*
Y156387D01*
X269833Y156573D01*
X269958Y156733D01*
X270125Y156867D01*
G01X269750Y158400D02*
X272250D01*
X271750Y158080D01*
G01X269750D02*
Y158720D01*
G01X271833Y160093D02*
X272083Y160253D01*
X272208Y160440D01*
X272250Y160653D01*
X272167Y160920D01*
X271958Y161107D01*
X271708Y161160D01*
X271458Y161133D01*
X271250Y161027D01*
X270833Y160493D01*
X270542Y160253D01*
X270125Y160093D01*
X269750Y160040D01*
Y161160D01*
G01X270042Y162347D02*
X269833Y162533D01*
X269750Y162747D01*
X269833Y162960D01*
X270083Y163147D01*
X270458Y163280D01*
X270833Y163333D01*
X271292D01*
X271667Y163280D01*
X272000Y163147D01*
X272167Y162987D01*
X272250Y162800D01*
X272167Y162587D01*
X272000Y162427D01*
X271750Y162320D01*
X271417Y162267D01*
X271125Y162320D01*
X270833Y162453D01*
X270667Y162613D01*
X270625Y162800D01*
X270708Y163013D01*
X270917Y163173D01*
X271292Y163333D01*
G01X262832Y155977D02*
X262957Y155817D01*
X263040Y155630D01*
Y155417D01*
X262915Y155177D01*
X262707Y154990D01*
X262457Y154857D01*
X262040Y154750D01*
X261665Y154723D01*
X261290Y154777D01*
X261040Y154857D01*
X260790Y155017D01*
X260623Y155203D01*
X260540Y155390D01*
Y155577D01*
X260623Y155763D01*
X260748Y155923D01*
X260915Y156057D01*
G01X260540Y157590D02*
X263040D01*
X262540Y157270D01*
G01X260540D02*
Y157910D01*
G01X261582Y159283D02*
X261873Y159470D01*
X262040Y159630D01*
X262123Y159843D01*
X262040Y160030D01*
X261873Y160163D01*
X261623Y160270D01*
X261332Y160297D01*
X261082Y160270D01*
X260832Y160163D01*
X260623Y160003D01*
X260540Y159817D01*
X260623Y159603D01*
X260873Y159417D01*
X261248Y159310D01*
X261665Y159283D01*
X262207Y159337D01*
X262498Y159417D01*
X262790Y159550D01*
X262998Y159737D01*
X263040Y159923D01*
X262957Y160110D01*
X262748Y160243D01*
G01X261582Y161483D02*
X261873Y161670D01*
X262040Y161830D01*
X262123Y162043D01*
X262040Y162230D01*
X261873Y162363D01*
X261623Y162470D01*
X261332Y162497D01*
X261082Y162470D01*
X260832Y162363D01*
X260623Y162203D01*
X260540Y162017D01*
X260623Y161803D01*
X260873Y161617D01*
X261248Y161510D01*
X261665Y161483D01*
X262207Y161537D01*
X262498Y161617D01*
X262790Y161750D01*
X262998Y161937D01*
X263040Y162123D01*
X262957Y162310D01*
X262748Y162443D01*
G01X263213Y166042D02*
X263373Y166167D01*
X263560Y166250D01*
X263773D01*
X264013Y166125D01*
X264200Y165917D01*
X264333Y165667D01*
X264440Y165250D01*
X264467Y164875D01*
X264413Y164500D01*
X264333Y164250D01*
X264173Y164000D01*
X263987Y163833D01*
X263800Y163750D01*
X263613D01*
X263427Y163833D01*
X263267Y163958D01*
X263133Y164125D01*
G01X261600Y163750D02*
Y166250D01*
X261920Y165750D01*
G01Y163750D02*
X261280D01*
G01X259400Y166250D02*
X259613Y166167D01*
X259773Y165958D01*
X259880Y165708D01*
X259960Y165375D01*
X259987Y165000D01*
X259960Y164625D01*
X259880Y164292D01*
X259773Y164042D01*
X259613Y163833D01*
X259400Y163750D01*
X259187Y163833D01*
X259027Y164042D01*
X258920Y164292D01*
X258840Y164625D01*
X258813Y165000D01*
X258840Y165375D01*
X258920Y165708D01*
X259027Y165958D01*
X259187Y166167D01*
X259400Y166250D01*
G01X257653Y164042D02*
X257467Y163833D01*
X257253Y163750D01*
X257040Y163833D01*
X256853Y164083D01*
X256720Y164458D01*
X256667Y164833D01*
Y165292D01*
X256720Y165667D01*
X256853Y166000D01*
X257013Y166167D01*
X257200Y166250D01*
X257413Y166167D01*
X257573Y166000D01*
X257680Y165750D01*
X257733Y165417D01*
X257680Y165125D01*
X257547Y164833D01*
X257387Y164667D01*
X257200Y164625D01*
X256987Y164708D01*
X256827Y164917D01*
X256667Y165292D01*
G01X262843Y153022D02*
X263003Y153147D01*
X263190Y153230D01*
X263403D01*
X263643Y153105D01*
X263830Y152897D01*
X263963Y152647D01*
X264070Y152230D01*
X264097Y151855D01*
X264043Y151480D01*
X263963Y151230D01*
X263803Y150980D01*
X263617Y150813D01*
X263430Y150730D01*
X263243D01*
X263057Y150813D01*
X262897Y150938D01*
X262763Y151105D01*
G01X261230Y150730D02*
Y153230D01*
X261550Y152730D01*
G01Y150730D02*
X260910D01*
G01X258710D02*
Y153230D01*
X259697Y151438D01*
X258363D01*
G01X256830Y150730D02*
Y153230D01*
X257150Y152730D01*
G01Y150730D02*
X256510D01*
G01X266213Y169542D02*
X266373Y169667D01*
X266560Y169750D01*
X266773D01*
X267013Y169625D01*
X267200Y169417D01*
X267333Y169167D01*
X267440Y168750D01*
X267467Y168375D01*
X267413Y168000D01*
X267333Y167750D01*
X267173Y167500D01*
X266987Y167333D01*
X266800Y167250D01*
X266613D01*
X266427Y167333D01*
X266267Y167458D01*
X266133Y167625D01*
G01X265107Y169333D02*
X264947Y169583D01*
X264760Y169708D01*
X264547Y169750D01*
X264280Y169667D01*
X264093Y169458D01*
X264040Y169208D01*
X264067Y168958D01*
X264173Y168750D01*
X264707Y168333D01*
X264947Y168042D01*
X265107Y167625D01*
X265160Y167250D01*
X264040D01*
G01X262400D02*
Y169750D01*
X262720Y169250D01*
G01Y167250D02*
X262080D01*
G01X260707Y169333D02*
X260547Y169583D01*
X260360Y169708D01*
X260147Y169750D01*
X259880Y169667D01*
X259693Y169458D01*
X259640Y169208D01*
X259667Y168958D01*
X259773Y168750D01*
X260307Y168333D01*
X260547Y168042D01*
X260707Y167625D01*
X260760Y167250D01*
X259640D01*
G01X262542Y172287D02*
X262667Y172127D01*
X262750Y171940D01*
Y171727D01*
X262625Y171487D01*
X262417Y171300D01*
X262167Y171167D01*
X261750Y171060D01*
X261375Y171033D01*
X261000Y171087D01*
X260750Y171167D01*
X260500Y171327D01*
X260333Y171513D01*
X260250Y171700D01*
Y171887D01*
X260333Y172073D01*
X260458Y172233D01*
X260625Y172367D01*
G01X260250Y173900D02*
X262750D01*
X262250Y173580D01*
G01X260250D02*
Y174220D01*
G01Y176100D02*
X262750D01*
X262250Y175780D01*
G01X260250D02*
Y176420D01*
G01X260625Y177713D02*
X260417Y177873D01*
X260292Y178060D01*
X260250Y178300D01*
X260333Y178540D01*
X260500Y178727D01*
X260792Y178860D01*
X261125Y178887D01*
X261458Y178833D01*
X261667Y178700D01*
X261833Y178513D01*
X261875Y178327D01*
X261833Y178140D01*
X261667Y177900D01*
X262750Y177980D01*
Y178700D01*
G01X276623Y169242D02*
X276783Y169367D01*
X276970Y169450D01*
X277183D01*
X277423Y169325D01*
X277610Y169117D01*
X277743Y168867D01*
X277850Y168450D01*
X277877Y168075D01*
X277823Y167700D01*
X277743Y167450D01*
X277583Y167200D01*
X277397Y167033D01*
X277210Y166950D01*
X277023D01*
X276837Y167033D01*
X276677Y167158D01*
X276543Y167325D01*
G01X275010Y166950D02*
Y169450D01*
X275330Y168950D01*
G01Y166950D02*
X274690D01*
G01X273317Y169033D02*
X273157Y169283D01*
X272970Y169408D01*
X272757Y169450D01*
X272490Y169367D01*
X272303Y169158D01*
X272250Y168908D01*
X272277Y168658D01*
X272383Y168450D01*
X272917Y168033D01*
X273157Y167742D01*
X273317Y167325D01*
X273370Y166950D01*
X272250D01*
G01X270610D02*
X270423Y166992D01*
X270210Y167117D01*
X270077Y167325D01*
X270023Y167617D01*
X270077Y167908D01*
X270237Y168158D01*
X270477Y168283D01*
X270743D01*
X270903Y168367D01*
X271037Y168575D01*
X271090Y168867D01*
X271010Y169158D01*
X270823Y169367D01*
X270610Y169450D01*
X270397Y169367D01*
X270210Y169158D01*
X270130Y168867D01*
X270183Y168575D01*
X270317Y168367D01*
X270477Y168283D01*
X270743D01*
X270983Y168158D01*
X271143Y167908D01*
X271197Y167617D01*
X271143Y167325D01*
X271010Y167117D01*
X270797Y166992D01*
X270610Y166950D01*
G01X271213Y177542D02*
X271373Y177667D01*
X271560Y177750D01*
X271773D01*
X272013Y177625D01*
X272200Y177417D01*
X272333Y177167D01*
X272440Y176750D01*
X272467Y176375D01*
X272413Y176000D01*
X272333Y175750D01*
X272173Y175500D01*
X271987Y175333D01*
X271800Y175250D01*
X271613D01*
X271427Y175333D01*
X271267Y175458D01*
X271133Y175625D01*
G01X270107Y177333D02*
X269947Y177583D01*
X269760Y177708D01*
X269547Y177750D01*
X269280Y177667D01*
X269093Y177458D01*
X269040Y177208D01*
X269067Y176958D01*
X269173Y176750D01*
X269707Y176333D01*
X269947Y176042D01*
X270107Y175625D01*
X270160Y175250D01*
X269040D01*
G01X267400Y177750D02*
X267613Y177667D01*
X267773Y177458D01*
X267880Y177208D01*
X267960Y176875D01*
X267987Y176500D01*
X267960Y176125D01*
X267880Y175792D01*
X267773Y175542D01*
X267613Y175333D01*
X267400Y175250D01*
X267187Y175333D01*
X267027Y175542D01*
X266920Y175792D01*
X266840Y176125D01*
X266813Y176500D01*
X266840Y176875D01*
X266920Y177208D01*
X267027Y177458D01*
X267187Y177667D01*
X267400Y177750D01*
G01X265707Y176292D02*
X265520Y176583D01*
X265360Y176750D01*
X265147Y176833D01*
X264960Y176750D01*
X264827Y176583D01*
X264720Y176333D01*
X264693Y176042D01*
X264720Y175792D01*
X264827Y175542D01*
X264987Y175333D01*
X265173Y175250D01*
X265387Y175333D01*
X265573Y175583D01*
X265680Y175958D01*
X265707Y176375D01*
X265653Y176917D01*
X265573Y177208D01*
X265440Y177500D01*
X265253Y177708D01*
X265067Y177750D01*
X264880Y177667D01*
X264747Y177458D01*
G01X276367Y192950D02*
Y196050D01*
X275408D01*
X275102Y195895D01*
X274910Y195688D01*
X274833Y195275D01*
X274910Y194862D01*
X275140Y194603D01*
X275408Y194448D01*
X276367D01*
G01X275408D02*
X274833Y192950D01*
G01X272500D02*
X272232Y193002D01*
X271925Y193157D01*
X271733Y193415D01*
X271657Y193777D01*
X271733Y194138D01*
X271963Y194448D01*
X272308Y194603D01*
X272692D01*
X272922Y194707D01*
X273113Y194965D01*
X273190Y195327D01*
X273075Y195688D01*
X272807Y195947D01*
X272500Y196050D01*
X272193Y195947D01*
X271925Y195688D01*
X271810Y195327D01*
X271887Y194965D01*
X272078Y194707D01*
X272308Y194603D01*
X272692D01*
X273037Y194448D01*
X273267Y194138D01*
X273343Y193777D01*
X273267Y193415D01*
X273075Y193157D01*
X272768Y193002D01*
X272500Y192950D01*
G01X270052Y193312D02*
X269783Y193053D01*
X269477Y192950D01*
X269170Y193053D01*
X268902Y193363D01*
X268710Y193828D01*
X268633Y194293D01*
Y194862D01*
X268710Y195327D01*
X268902Y195740D01*
X269132Y195947D01*
X269400Y196050D01*
X269707Y195947D01*
X269937Y195740D01*
X270090Y195430D01*
X270167Y195017D01*
X270090Y194655D01*
X269898Y194293D01*
X269668Y194087D01*
X269400Y194035D01*
X269093Y194138D01*
X268863Y194397D01*
X268633Y194862D01*
G01X260292Y215243D02*
X260447Y215013D01*
X260550Y214745D01*
Y214438D01*
X260395Y214093D01*
X260137Y213825D01*
X259827Y213633D01*
X259310Y213480D01*
X258845Y213442D01*
X258380Y213518D01*
X258070Y213633D01*
X257760Y213863D01*
X257553Y214132D01*
X257450Y214400D01*
Y214668D01*
X257553Y214937D01*
X257708Y215167D01*
X257915Y215358D01*
G01X258742Y216772D02*
X259103Y217040D01*
X259310Y217270D01*
X259413Y217577D01*
X259310Y217845D01*
X259103Y218037D01*
X258793Y218190D01*
X258432Y218228D01*
X258122Y218190D01*
X257812Y218037D01*
X257553Y217807D01*
X257450Y217538D01*
X257553Y217232D01*
X257863Y216963D01*
X258328Y216810D01*
X258845Y216772D01*
X259517Y216848D01*
X259878Y216963D01*
X260240Y217155D01*
X260498Y217423D01*
X260550Y217692D01*
X260447Y217960D01*
X260188Y218152D01*
G01X257812Y219948D02*
X257553Y220217D01*
X257450Y220523D01*
X257553Y220830D01*
X257863Y221098D01*
X258328Y221290D01*
X258793Y221367D01*
X259362D01*
X259827Y221290D01*
X260240Y221098D01*
X260447Y220868D01*
X260550Y220600D01*
X260447Y220293D01*
X260240Y220063D01*
X259930Y219910D01*
X259517Y219833D01*
X259155Y219910D01*
X258793Y220102D01*
X258587Y220332D01*
X258535Y220600D01*
X258638Y220907D01*
X258897Y221137D01*
X259362Y221367D01*
G01X277443Y211050D02*
Y208828D01*
X277290Y208363D01*
X276983Y208053D01*
X276600Y207950D01*
X276217Y208053D01*
X275910Y208363D01*
X275757Y208828D01*
Y211050D01*
G01X273500Y207950D02*
Y211050D01*
X273960Y210430D01*
G01Y207950D02*
X273040D01*
G01X271128Y210533D02*
X270898Y210843D01*
X270630Y210998D01*
X270323Y211050D01*
X269940Y210947D01*
X269672Y210688D01*
X269595Y210378D01*
X269633Y210068D01*
X269787Y209810D01*
X270553Y209293D01*
X270898Y208932D01*
X271128Y208415D01*
X271205Y207950D01*
X269595D01*
G01X263087Y210250D02*
X262927Y209958D01*
X262713Y209792D01*
X262473Y209750D01*
X262260Y209792D01*
X262047Y210000D01*
X261913Y210250D01*
X261887Y210500D01*
X261940Y210792D01*
X262127Y211000D01*
X262313Y211083D01*
X262553D01*
G01X262313D02*
X262153Y211208D01*
X262020Y211417D01*
X261967Y211667D01*
X262020Y211917D01*
X262153Y212125D01*
X262393Y212250D01*
X262633Y212208D01*
X262873Y212042D01*
G01X258250Y234320D02*
X260750D01*
X258958Y233333D01*
Y234667D01*
G01X280542Y49887D02*
X280667Y49727D01*
X280750Y49540D01*
Y49327D01*
X280625Y49087D01*
X280417Y48900D01*
X280167Y48767D01*
X279750Y48660D01*
X279375Y48633D01*
X279000Y48687D01*
X278750Y48767D01*
X278500Y48927D01*
X278333Y49113D01*
X278250Y49300D01*
Y49487D01*
X278333Y49673D01*
X278458Y49833D01*
X278625Y49967D01*
G01X280333Y50993D02*
X280583Y51153D01*
X280708Y51340D01*
X280750Y51553D01*
X280667Y51820D01*
X280458Y52007D01*
X280208Y52060D01*
X279958Y52033D01*
X279750Y51927D01*
X279333Y51393D01*
X279042Y51153D01*
X278625Y50993D01*
X278250Y50940D01*
Y52060D01*
G01Y53700D02*
X278292Y53887D01*
X278417Y54100D01*
X278625Y54233D01*
X278917Y54287D01*
X279208Y54233D01*
X279458Y54073D01*
X279583Y53833D01*
Y53567D01*
X279667Y53407D01*
X279875Y53273D01*
X280167Y53220D01*
X280458Y53300D01*
X280667Y53487D01*
X280750Y53700D01*
X280667Y53913D01*
X280458Y54100D01*
X280167Y54180D01*
X279875Y54127D01*
X279667Y53993D01*
X279583Y53833D01*
Y53567D01*
X279458Y53327D01*
X279208Y53167D01*
X278917Y53113D01*
X278625Y53167D01*
X278417Y53300D01*
X278292Y53513D01*
X278250Y53700D01*
G01X286542Y49887D02*
X286667Y49727D01*
X286750Y49540D01*
Y49327D01*
X286625Y49087D01*
X286417Y48900D01*
X286167Y48767D01*
X285750Y48660D01*
X285375Y48633D01*
X285000Y48687D01*
X284750Y48767D01*
X284500Y48927D01*
X284333Y49113D01*
X284250Y49300D01*
Y49487D01*
X284333Y49673D01*
X284458Y49833D01*
X284625Y49967D01*
G01X284750Y50913D02*
X284458Y51073D01*
X284292Y51287D01*
X284250Y51527D01*
X284292Y51740D01*
X284500Y51953D01*
X284750Y52087D01*
X285000Y52113D01*
X285292Y52060D01*
X285500Y51873D01*
X285583Y51687D01*
Y51447D01*
G01Y51687D02*
X285708Y51847D01*
X285917Y51980D01*
X286167Y52033D01*
X286417Y51980D01*
X286625Y51847D01*
X286750Y51607D01*
X286708Y51367D01*
X286542Y51127D01*
G01X284250Y54020D02*
X286750D01*
X284958Y53033D01*
Y54367D01*
G01X288042Y133450D02*
X289000Y136550D01*
X289958Y133450D01*
G01X289613Y134535D02*
X288387D01*
G01X282600Y141700D02*
Y131100D01*
G01X286200Y138500D02*
X290800D01*
G01X293400Y141700D02*
X282600D01*
G01X283963Y164842D02*
X284123Y164967D01*
X284310Y165050D01*
X284523D01*
X284763Y164925D01*
X284950Y164717D01*
X285083Y164467D01*
X285190Y164050D01*
X285217Y163675D01*
X285163Y163300D01*
X285083Y163050D01*
X284923Y162800D01*
X284737Y162633D01*
X284550Y162550D01*
X284363D01*
X284177Y162633D01*
X284017Y162758D01*
X283883Y162925D01*
G01X282350Y162550D02*
Y165050D01*
X282670Y164550D01*
G01Y162550D02*
X282030D01*
G01X280737Y163050D02*
X280577Y162758D01*
X280363Y162592D01*
X280123Y162550D01*
X279910Y162592D01*
X279697Y162800D01*
X279563Y163050D01*
X279537Y163300D01*
X279590Y163592D01*
X279777Y163800D01*
X279963Y163883D01*
X280203D01*
G01X279963D02*
X279803Y164008D01*
X279670Y164217D01*
X279617Y164467D01*
X279670Y164717D01*
X279803Y164925D01*
X280043Y165050D01*
X280283Y165008D01*
X280523Y164842D01*
G01X277950Y162550D02*
X277763Y162592D01*
X277550Y162717D01*
X277417Y162925D01*
X277363Y163217D01*
X277417Y163508D01*
X277577Y163758D01*
X277817Y163883D01*
X278083D01*
X278243Y163967D01*
X278377Y164175D01*
X278430Y164467D01*
X278350Y164758D01*
X278163Y164967D01*
X277950Y165050D01*
X277737Y164967D01*
X277550Y164758D01*
X277470Y164467D01*
X277523Y164175D01*
X277657Y163967D01*
X277817Y163883D01*
X278083D01*
X278323Y163758D01*
X278483Y163508D01*
X278537Y163217D01*
X278483Y162925D01*
X278350Y162717D01*
X278137Y162592D01*
X277950Y162550D01*
G01X276082Y150537D02*
X276207Y150377D01*
X276290Y150190D01*
Y149977D01*
X276165Y149737D01*
X275957Y149550D01*
X275707Y149417D01*
X275290Y149310D01*
X274915Y149283D01*
X274540Y149337D01*
X274290Y149417D01*
X274040Y149577D01*
X273873Y149763D01*
X273790Y149950D01*
Y150137D01*
X273873Y150323D01*
X273998Y150483D01*
X274165Y150617D01*
G01X273790Y152150D02*
X276290D01*
X275790Y151830D01*
G01X273790D02*
Y152470D01*
G01Y154297D02*
X274332Y154350D01*
X274790Y154430D01*
X275207Y154537D01*
X275665Y154670D01*
X276290Y154883D01*
Y153817D01*
G01X273790Y156550D02*
X276290D01*
X275790Y156230D01*
G01X273790D02*
Y156870D01*
G01X289042Y158787D02*
X289167Y158627D01*
X289250Y158440D01*
Y158227D01*
X289125Y157987D01*
X288917Y157800D01*
X288667Y157667D01*
X288250Y157560D01*
X287875Y157533D01*
X287500Y157587D01*
X287250Y157667D01*
X287000Y157827D01*
X286833Y158013D01*
X286750Y158200D01*
Y158387D01*
X286833Y158573D01*
X286958Y158733D01*
X287125Y158867D01*
G01X288833Y159893D02*
X289083Y160053D01*
X289208Y160240D01*
X289250Y160453D01*
X289167Y160720D01*
X288958Y160907D01*
X288708Y160960D01*
X288458Y160933D01*
X288250Y160827D01*
X287833Y160293D01*
X287542Y160053D01*
X287125Y159893D01*
X286750Y159840D01*
Y160960D01*
G01X289250Y162600D02*
X289167Y162387D01*
X288958Y162227D01*
X288708Y162120D01*
X288375Y162040D01*
X288000Y162013D01*
X287625Y162040D01*
X287292Y162120D01*
X287042Y162227D01*
X286833Y162387D01*
X286750Y162600D01*
X286833Y162813D01*
X287042Y162973D01*
X287292Y163080D01*
X287625Y163160D01*
X288000Y163187D01*
X288375Y163160D01*
X288708Y163080D01*
X288958Y162973D01*
X289167Y162813D01*
X289250Y162600D01*
G01X286750Y164747D02*
X287292Y164800D01*
X287750Y164880D01*
X288167Y164987D01*
X288625Y165120D01*
X289250Y165333D01*
Y164267D01*
G01X283962Y150537D02*
X284087Y150377D01*
X284170Y150190D01*
Y149977D01*
X284045Y149737D01*
X283837Y149550D01*
X283587Y149417D01*
X283170Y149310D01*
X282795Y149283D01*
X282420Y149337D01*
X282170Y149417D01*
X281920Y149577D01*
X281753Y149763D01*
X281670Y149950D01*
Y150137D01*
X281753Y150323D01*
X281878Y150483D01*
X282045Y150617D01*
G01X281670Y152150D02*
X284170D01*
X283670Y151830D01*
G01X281670D02*
Y152470D01*
G01X282045Y153763D02*
X281837Y153923D01*
X281712Y154110D01*
X281670Y154350D01*
X281753Y154590D01*
X281920Y154777D01*
X282212Y154910D01*
X282545Y154937D01*
X282878Y154883D01*
X283087Y154750D01*
X283253Y154563D01*
X283295Y154377D01*
X283253Y154190D01*
X283087Y153950D01*
X284170Y154030D01*
Y154750D01*
G01X283753Y156043D02*
X284003Y156203D01*
X284128Y156390D01*
X284170Y156603D01*
X284087Y156870D01*
X283878Y157057D01*
X283628Y157110D01*
X283378Y157083D01*
X283170Y156977D01*
X282753Y156443D01*
X282462Y156203D01*
X282045Y156043D01*
X281670Y155990D01*
Y157110D01*
G01X283963Y160902D02*
X284123Y161027D01*
X284310Y161110D01*
X284523D01*
X284763Y160985D01*
X284950Y160777D01*
X285083Y160527D01*
X285190Y160110D01*
X285217Y159735D01*
X285163Y159360D01*
X285083Y159110D01*
X284923Y158860D01*
X284737Y158693D01*
X284550Y158610D01*
X284363D01*
X284177Y158693D01*
X284017Y158818D01*
X283883Y158985D01*
G01X282350Y158610D02*
Y161110D01*
X282670Y160610D01*
G01Y158610D02*
X282030D01*
G01X279830D02*
Y161110D01*
X280817Y159318D01*
X279483D01*
G01X278003Y158610D02*
X277950Y159152D01*
X277870Y159610D01*
X277763Y160027D01*
X277630Y160485D01*
X277417Y161110D01*
X278483D01*
G01X280022Y150537D02*
X280147Y150377D01*
X280230Y150190D01*
Y149977D01*
X280105Y149737D01*
X279897Y149550D01*
X279647Y149417D01*
X279230Y149310D01*
X278855Y149283D01*
X278480Y149337D01*
X278230Y149417D01*
X277980Y149577D01*
X277813Y149763D01*
X277730Y149950D01*
Y150137D01*
X277813Y150323D01*
X277938Y150483D01*
X278105Y150617D01*
G01X277730Y152150D02*
X280230D01*
X279730Y151830D01*
G01X277730D02*
Y152470D01*
G01X278772Y153843D02*
X279063Y154030D01*
X279230Y154190D01*
X279313Y154403D01*
X279230Y154590D01*
X279063Y154723D01*
X278813Y154830D01*
X278522Y154857D01*
X278272Y154830D01*
X278022Y154723D01*
X277813Y154563D01*
X277730Y154377D01*
X277813Y154163D01*
X278063Y153977D01*
X278438Y153870D01*
X278855Y153843D01*
X279397Y153897D01*
X279688Y153977D01*
X279980Y154110D01*
X280188Y154297D01*
X280230Y154483D01*
X280147Y154670D01*
X279938Y154803D01*
G01X277730Y156550D02*
X280230D01*
X279730Y156230D01*
G01X277730D02*
Y156870D01*
G01X276082Y159417D02*
X276207Y159257D01*
X276290Y159070D01*
Y158857D01*
X276165Y158617D01*
X275957Y158430D01*
X275707Y158297D01*
X275290Y158190D01*
X274915Y158163D01*
X274540Y158217D01*
X274290Y158297D01*
X274040Y158457D01*
X273873Y158643D01*
X273790Y158830D01*
Y159017D01*
X273873Y159203D01*
X273998Y159363D01*
X274165Y159497D01*
G01X275873Y160523D02*
X276123Y160683D01*
X276248Y160870D01*
X276290Y161083D01*
X276207Y161350D01*
X275998Y161537D01*
X275748Y161590D01*
X275498Y161563D01*
X275290Y161457D01*
X274873Y160923D01*
X274582Y160683D01*
X274165Y160523D01*
X273790Y160470D01*
Y161590D01*
G01X276290Y163230D02*
X276207Y163017D01*
X275998Y162857D01*
X275748Y162750D01*
X275415Y162670D01*
X275040Y162643D01*
X274665Y162670D01*
X274332Y162750D01*
X274082Y162857D01*
X273873Y163017D01*
X273790Y163230D01*
X273873Y163443D01*
X274082Y163603D01*
X274332Y163710D01*
X274665Y163790D01*
X275040Y163817D01*
X275415Y163790D01*
X275748Y163710D01*
X275998Y163603D01*
X276207Y163443D01*
X276290Y163230D01*
G01X273790Y165430D02*
X276290D01*
X275790Y165110D01*
G01X273790D02*
Y165750D01*
G01X286713Y169042D02*
X286873Y169167D01*
X287060Y169250D01*
X287273D01*
X287513Y169125D01*
X287700Y168917D01*
X287833Y168667D01*
X287940Y168250D01*
X287967Y167875D01*
X287913Y167500D01*
X287833Y167250D01*
X287673Y167000D01*
X287487Y166833D01*
X287300Y166750D01*
X287113D01*
X286927Y166833D01*
X286767Y166958D01*
X286633Y167125D01*
G01X285100Y166750D02*
Y169250D01*
X285420Y168750D01*
G01Y166750D02*
X284780D01*
G01X283407Y167792D02*
X283220Y168083D01*
X283060Y168250D01*
X282847Y168333D01*
X282660Y168250D01*
X282527Y168083D01*
X282420Y167833D01*
X282393Y167542D01*
X282420Y167292D01*
X282527Y167042D01*
X282687Y166833D01*
X282873Y166750D01*
X283087Y166833D01*
X283273Y167083D01*
X283380Y167458D01*
X283407Y167875D01*
X283353Y168417D01*
X283273Y168708D01*
X283140Y169000D01*
X282953Y169208D01*
X282767Y169250D01*
X282580Y169167D01*
X282447Y168958D01*
G01X281287Y167125D02*
X281127Y166917D01*
X280940Y166792D01*
X280700Y166750D01*
X280460Y166833D01*
X280273Y167000D01*
X280140Y167292D01*
X280113Y167625D01*
X280167Y167958D01*
X280300Y168167D01*
X280487Y168333D01*
X280673Y168375D01*
X280860Y168333D01*
X281100Y168167D01*
X281020Y169250D01*
X280300D01*
G01X283542Y171787D02*
X283667Y171627D01*
X283750Y171440D01*
Y171227D01*
X283625Y170987D01*
X283417Y170800D01*
X283167Y170667D01*
X282750Y170560D01*
X282375Y170533D01*
X282000Y170587D01*
X281750Y170667D01*
X281500Y170827D01*
X281333Y171013D01*
X281250Y171200D01*
Y171387D01*
X281333Y171573D01*
X281458Y171733D01*
X281625Y171867D01*
G01X281250Y173400D02*
X283750D01*
X283250Y173080D01*
G01X281250D02*
Y173720D01*
G01X283750Y175600D02*
X283667Y175387D01*
X283458Y175227D01*
X283208Y175120D01*
X282875Y175040D01*
X282500Y175013D01*
X282125Y175040D01*
X281792Y175120D01*
X281542Y175227D01*
X281333Y175387D01*
X281250Y175600D01*
X281333Y175813D01*
X281542Y175973D01*
X281792Y176080D01*
X282125Y176160D01*
X282500Y176187D01*
X282875Y176160D01*
X283208Y176080D01*
X283458Y175973D01*
X283667Y175813D01*
X283750Y175600D01*
G01X281250Y177747D02*
X281792Y177800D01*
X282250Y177880D01*
X282667Y177987D01*
X283125Y178120D01*
X283750Y178333D01*
Y177267D01*
G01X273746Y170541D02*
X276246D01*
Y171207D01*
X276121Y171421D01*
X275954Y171554D01*
X275621Y171607D01*
X275288Y171554D01*
X275079Y171394D01*
X274954Y171207D01*
Y170541D01*
G01Y171207D02*
X273746Y171607D01*
G01Y173594D02*
X276246D01*
X274454Y172607D01*
Y173941D01*
G01X274246Y174887D02*
X273954Y175047D01*
X273788Y175261D01*
X273746Y175501D01*
X273788Y175714D01*
X273996Y175927D01*
X274246Y176061D01*
X274496Y176087D01*
X274788Y176034D01*
X274996Y175847D01*
X275079Y175661D01*
Y175421D01*
G01Y175661D02*
X275204Y175821D01*
X275413Y175954D01*
X275663Y176007D01*
X275913Y175954D01*
X276121Y175821D01*
X276246Y175581D01*
X276204Y175341D01*
X276038Y175101D01*
G01X274788Y177167D02*
X275079Y177354D01*
X275246Y177514D01*
X275329Y177727D01*
X275246Y177914D01*
X275079Y178047D01*
X274829Y178154D01*
X274538Y178181D01*
X274288Y178154D01*
X274038Y178047D01*
X273829Y177887D01*
X273746Y177701D01*
X273829Y177487D01*
X274079Y177301D01*
X274454Y177194D01*
X274871Y177167D01*
X275413Y177221D01*
X275704Y177301D01*
X275996Y177434D01*
X276204Y177621D01*
X276246Y177807D01*
X276163Y177994D01*
X275954Y178127D01*
G01X277250Y170667D02*
X279750D01*
Y171333D01*
X279625Y171547D01*
X279458Y171680D01*
X279125Y171733D01*
X278792Y171680D01*
X278583Y171520D01*
X278458Y171333D01*
Y170667D01*
G01Y171333D02*
X277250Y171733D01*
G01Y173720D02*
X279750D01*
X277958Y172733D01*
Y174067D01*
G01X277750Y175013D02*
X277458Y175173D01*
X277292Y175387D01*
X277250Y175627D01*
X277292Y175840D01*
X277500Y176053D01*
X277750Y176187D01*
X278000Y176213D01*
X278292Y176160D01*
X278500Y175973D01*
X278583Y175787D01*
Y175547D01*
G01Y175787D02*
X278708Y175947D01*
X278917Y176080D01*
X279167Y176133D01*
X279417Y176080D01*
X279625Y175947D01*
X279750Y175707D01*
X279708Y175467D01*
X279542Y175227D01*
G01X277250Y177747D02*
X277792Y177800D01*
X278250Y177880D01*
X278667Y177987D01*
X279125Y178120D01*
X279750Y178333D01*
Y177267D01*
G01X292833Y172750D02*
Y175250D01*
X292167D01*
X291953Y175125D01*
X291820Y174958D01*
X291767Y174625D01*
X291820Y174292D01*
X291980Y174083D01*
X292167Y173958D01*
X292833D01*
G01X292167D02*
X291767Y172750D01*
G01X290687Y173125D02*
X290527Y172917D01*
X290340Y172792D01*
X290100Y172750D01*
X289860Y172833D01*
X289673Y173000D01*
X289540Y173292D01*
X289513Y173625D01*
X289567Y173958D01*
X289700Y174167D01*
X289887Y174333D01*
X290073Y174375D01*
X290260Y174333D01*
X290500Y174167D01*
X290420Y175250D01*
X289700D01*
G01X287900D02*
X288113Y175167D01*
X288273Y174958D01*
X288380Y174708D01*
X288460Y174375D01*
X288487Y174000D01*
X288460Y173625D01*
X288380Y173292D01*
X288273Y173042D01*
X288113Y172833D01*
X287900Y172750D01*
X287687Y172833D01*
X287527Y173042D01*
X287420Y173292D01*
X287340Y173625D01*
X287313Y174000D01*
X287340Y174375D01*
X287420Y174708D01*
X287527Y174958D01*
X287687Y175167D01*
X287900Y175250D01*
G01X286207Y174833D02*
X286047Y175083D01*
X285860Y175208D01*
X285647Y175250D01*
X285380Y175167D01*
X285193Y174958D01*
X285140Y174708D01*
X285167Y174458D01*
X285273Y174250D01*
X285807Y173833D01*
X286047Y173542D01*
X286207Y173125D01*
X286260Y172750D01*
X285140D01*
G01X292833Y176450D02*
Y178950D01*
X292167D01*
X291953Y178825D01*
X291820Y178658D01*
X291767Y178325D01*
X291820Y177992D01*
X291980Y177783D01*
X292167Y177658D01*
X292833D01*
G01X292167D02*
X291767Y176450D01*
G01X290607Y178533D02*
X290447Y178783D01*
X290260Y178908D01*
X290047Y178950D01*
X289780Y178867D01*
X289593Y178658D01*
X289540Y178408D01*
X289567Y178158D01*
X289673Y177950D01*
X290207Y177533D01*
X290447Y177242D01*
X290607Y176825D01*
X290660Y176450D01*
X289540D01*
G01X287953D02*
X287900Y176992D01*
X287820Y177450D01*
X287713Y177867D01*
X287580Y178325D01*
X287367Y178950D01*
X288433D01*
G01X285700D02*
X285913Y178867D01*
X286073Y178658D01*
X286180Y178408D01*
X286260Y178075D01*
X286287Y177700D01*
X286260Y177325D01*
X286180Y176992D01*
X286073Y176742D01*
X285913Y176533D01*
X285700Y176450D01*
X285487Y176533D01*
X285327Y176742D01*
X285220Y176992D01*
X285140Y177325D01*
X285113Y177700D01*
X285140Y178075D01*
X285220Y178408D01*
X285327Y178658D01*
X285487Y178867D01*
X285700Y178950D01*
G01X273950Y182133D02*
X277050D01*
Y183092D01*
X276895Y183398D01*
X276688Y183590D01*
X276275Y183667D01*
X275862Y183590D01*
X275603Y183360D01*
X275448Y183092D01*
Y182133D01*
G01Y183092D02*
X273950Y183667D01*
G01X274312Y185348D02*
X274053Y185617D01*
X273950Y185923D01*
X274053Y186230D01*
X274363Y186498D01*
X274828Y186690D01*
X275293Y186767D01*
X275862D01*
X276327Y186690D01*
X276740Y186498D01*
X276947Y186268D01*
X277050Y186000D01*
X276947Y185693D01*
X276740Y185463D01*
X276430Y185310D01*
X276017Y185233D01*
X275655Y185310D01*
X275293Y185502D01*
X275087Y185732D01*
X275035Y186000D01*
X275138Y186307D01*
X275397Y186537D01*
X275862Y186767D01*
G01X277050Y189100D02*
X276947Y188793D01*
X276688Y188563D01*
X276378Y188410D01*
X275965Y188295D01*
X275500Y188257D01*
X275035Y188295D01*
X274622Y188410D01*
X274312Y188563D01*
X274053Y188793D01*
X273950Y189100D01*
X274053Y189407D01*
X274312Y189637D01*
X274622Y189790D01*
X275035Y189905D01*
X275500Y189943D01*
X275965Y189905D01*
X276378Y189790D01*
X276688Y189637D01*
X276947Y189407D01*
X277050Y189100D01*
G01X281292Y207743D02*
X281447Y207513D01*
X281550Y207245D01*
Y206938D01*
X281395Y206593D01*
X281137Y206325D01*
X280827Y206133D01*
X280310Y205980D01*
X279845Y205942D01*
X279380Y206018D01*
X279070Y206133D01*
X278760Y206363D01*
X278553Y206632D01*
X278450Y206900D01*
Y207168D01*
X278553Y207437D01*
X278708Y207667D01*
X278915Y207858D01*
G01X278450Y209923D02*
X279122Y210000D01*
X279690Y210115D01*
X280207Y210268D01*
X280775Y210460D01*
X281550Y210767D01*
Y209233D01*
G01X278450Y213100D02*
X281550D01*
X280930Y212640D01*
G01X278450D02*
Y213560D01*
G01X283450Y206172D02*
X286550D01*
Y207628D01*
G01X285052Y207092D02*
Y206172D01*
G01X286550Y209157D02*
X284328D01*
X283863Y209310D01*
X283553Y209617D01*
X283450Y210000D01*
X283553Y210383D01*
X283863Y210690D01*
X284328Y210843D01*
X286550D01*
G01X284070Y212257D02*
X283708Y212487D01*
X283502Y212793D01*
X283450Y213138D01*
X283502Y213445D01*
X283760Y213752D01*
X284070Y213943D01*
X284380Y213982D01*
X284742Y213905D01*
X285000Y213637D01*
X285103Y213368D01*
Y213023D01*
G01Y213368D02*
X285258Y213598D01*
X285517Y213790D01*
X285827Y213867D01*
X286137Y213790D01*
X286395Y213598D01*
X286550Y213253D01*
X286498Y212908D01*
X286292Y212563D01*
G01X275587Y235625D02*
X275427Y235417D01*
X275240Y235292D01*
X275000Y235250D01*
X274760Y235333D01*
X274573Y235500D01*
X274440Y235792D01*
X274413Y236125D01*
X274467Y236458D01*
X274600Y236667D01*
X274787Y236833D01*
X274973Y236875D01*
X275160Y236833D01*
X275400Y236667D01*
X275320Y237750D01*
X274600D01*
G01X289292Y299243D02*
X289447Y299013D01*
X289550Y298745D01*
Y298438D01*
X289395Y298093D01*
X289137Y297825D01*
X288827Y297633D01*
X288310Y297480D01*
X287845Y297442D01*
X287380Y297518D01*
X287070Y297633D01*
X286760Y297863D01*
X286553Y298132D01*
X286450Y298400D01*
Y298668D01*
X286553Y298937D01*
X286708Y299167D01*
X286915Y299358D01*
G01Y300657D02*
X286657Y300887D01*
X286502Y301155D01*
X286450Y301500D01*
X286553Y301845D01*
X286760Y302113D01*
X287122Y302305D01*
X287535Y302343D01*
X287948Y302267D01*
X288207Y302075D01*
X288413Y301807D01*
X288465Y301538D01*
X288413Y301270D01*
X288207Y300925D01*
X289550Y301040D01*
Y302075D01*
G01X286812Y303948D02*
X286553Y304217D01*
X286450Y304523D01*
X286553Y304830D01*
X286863Y305098D01*
X287328Y305290D01*
X287793Y305367D01*
X288362D01*
X288827Y305290D01*
X289240Y305098D01*
X289447Y304868D01*
X289550Y304600D01*
X289447Y304293D01*
X289240Y304063D01*
X288930Y303910D01*
X288517Y303833D01*
X288155Y303910D01*
X287793Y304102D01*
X287587Y304332D01*
X287535Y304600D01*
X287638Y304907D01*
X287897Y305137D01*
X288362Y305367D01*
G01X296867Y319450D02*
Y322550D01*
X295908D01*
X295602Y322395D01*
X295410Y322188D01*
X295333Y321775D01*
X295410Y321362D01*
X295640Y321103D01*
X295908Y320948D01*
X296867D01*
G01X295908D02*
X295333Y319450D01*
G01X293728Y320742D02*
X293460Y321103D01*
X293230Y321310D01*
X292923Y321413D01*
X292655Y321310D01*
X292463Y321103D01*
X292310Y320793D01*
X292272Y320432D01*
X292310Y320122D01*
X292463Y319812D01*
X292693Y319553D01*
X292962Y319450D01*
X293268Y319553D01*
X293537Y319863D01*
X293690Y320328D01*
X293728Y320845D01*
X293652Y321517D01*
X293537Y321878D01*
X293345Y322240D01*
X293077Y322498D01*
X292808Y322550D01*
X292540Y322447D01*
X292348Y322188D01*
G01X289900Y319450D02*
Y322550D01*
X290360Y321930D01*
G01Y319450D02*
X289440D01*
G01X296867Y323450D02*
Y326550D01*
X295908D01*
X295602Y326395D01*
X295410Y326188D01*
X295333Y325775D01*
X295410Y325362D01*
X295640Y325103D01*
X295908Y324948D01*
X296867D01*
G01X295908D02*
X295333Y323450D01*
G01X293728Y324742D02*
X293460Y325103D01*
X293230Y325310D01*
X292923Y325413D01*
X292655Y325310D01*
X292463Y325103D01*
X292310Y324793D01*
X292272Y324432D01*
X292310Y324122D01*
X292463Y323812D01*
X292693Y323553D01*
X292962Y323450D01*
X293268Y323553D01*
X293537Y323863D01*
X293690Y324328D01*
X293728Y324845D01*
X293652Y325517D01*
X293537Y325878D01*
X293345Y326240D01*
X293077Y326498D01*
X292808Y326550D01*
X292540Y326447D01*
X292348Y326188D01*
G01X290628Y326033D02*
X290398Y326343D01*
X290130Y326498D01*
X289823Y326550D01*
X289440Y326447D01*
X289172Y326188D01*
X289095Y325878D01*
X289133Y325568D01*
X289287Y325310D01*
X290053Y324793D01*
X290398Y324432D01*
X290628Y323915D01*
X290705Y323450D01*
X289095D01*
G01X306450Y29942D02*
X309550Y30900D01*
X306450Y31858D01*
G01X307535Y31513D02*
Y30287D01*
G01X307070Y33157D02*
X306708Y33387D01*
X306502Y33693D01*
X306450Y34038D01*
X306502Y34345D01*
X306760Y34652D01*
X307070Y34843D01*
X307380Y34882D01*
X307742Y34805D01*
X308000Y34537D01*
X308103Y34268D01*
Y33923D01*
G01Y34268D02*
X308258Y34498D01*
X308517Y34690D01*
X308827Y34767D01*
X309137Y34690D01*
X309395Y34498D01*
X309550Y34153D01*
X309498Y33808D01*
X309292Y33463D01*
G01X309033Y36372D02*
X309343Y36602D01*
X309498Y36870D01*
X309550Y37177D01*
X309447Y37560D01*
X309188Y37828D01*
X308878Y37905D01*
X308568Y37867D01*
X308310Y37713D01*
X307793Y36947D01*
X307432Y36602D01*
X306915Y36372D01*
X306450Y36295D01*
Y37905D01*
G01X308092Y65243D02*
X308247Y65013D01*
X308350Y64745D01*
Y64438D01*
X308195Y64093D01*
X307937Y63825D01*
X307627Y63633D01*
X307110Y63480D01*
X306645Y63442D01*
X306180Y63518D01*
X305870Y63633D01*
X305560Y63863D01*
X305353Y64132D01*
X305250Y64400D01*
Y64668D01*
X305353Y64937D01*
X305508Y65167D01*
X305715Y65358D01*
G01X305870Y66657D02*
X305508Y66887D01*
X305302Y67193D01*
X305250Y67538D01*
X305302Y67845D01*
X305560Y68152D01*
X305870Y68343D01*
X306180Y68382D01*
X306542Y68305D01*
X306800Y68037D01*
X306903Y67768D01*
Y67423D01*
G01Y67768D02*
X307058Y67998D01*
X307317Y68190D01*
X307627Y68267D01*
X307937Y68190D01*
X308195Y67998D01*
X308350Y67653D01*
X308298Y67308D01*
X308092Y66963D01*
G01X305715Y69757D02*
X305457Y69987D01*
X305302Y70255D01*
X305250Y70600D01*
X305353Y70945D01*
X305560Y71213D01*
X305922Y71405D01*
X306335Y71443D01*
X306748Y71367D01*
X307007Y71175D01*
X307213Y70907D01*
X307265Y70638D01*
X307213Y70370D01*
X307007Y70025D01*
X308350Y70140D01*
Y71175D01*
G01X290800Y138500D02*
X289400Y139700D01*
G01X290800Y138500D02*
X289300Y137300D01*
G01X297333Y238993D02*
X297583Y239153D01*
X297708Y239340D01*
X297750Y239553D01*
X297667Y239820D01*
X297458Y240007D01*
X297208Y240060D01*
X296958Y240033D01*
X296750Y239927D01*
X296333Y239393D01*
X296042Y239153D01*
X295625Y238993D01*
X295250Y238940D01*
Y240060D01*
G01X293792Y299243D02*
X293947Y299013D01*
X294050Y298745D01*
Y298438D01*
X293895Y298093D01*
X293637Y297825D01*
X293327Y297633D01*
X292810Y297480D01*
X292345Y297442D01*
X291880Y297518D01*
X291570Y297633D01*
X291260Y297863D01*
X291053Y298132D01*
X290950Y298400D01*
Y298668D01*
X291053Y298937D01*
X291208Y299167D01*
X291415Y299358D01*
G01X292242Y300772D02*
X292603Y301040D01*
X292810Y301270D01*
X292913Y301577D01*
X292810Y301845D01*
X292603Y302037D01*
X292293Y302190D01*
X291932Y302228D01*
X291622Y302190D01*
X291312Y302037D01*
X291053Y301807D01*
X290950Y301538D01*
X291053Y301232D01*
X291363Y300963D01*
X291828Y300810D01*
X292345Y300772D01*
X293017Y300848D01*
X293378Y300963D01*
X293740Y301155D01*
X293998Y301423D01*
X294050Y301692D01*
X293947Y301960D01*
X293688Y302152D01*
G01X294050Y304600D02*
X293947Y304293D01*
X293688Y304063D01*
X293378Y303910D01*
X292965Y303795D01*
X292500Y303757D01*
X292035Y303795D01*
X291622Y303910D01*
X291312Y304063D01*
X291053Y304293D01*
X290950Y304600D01*
X291053Y304907D01*
X291312Y305137D01*
X291622Y305290D01*
X292035Y305405D01*
X292500Y305443D01*
X292965Y305405D01*
X293378Y305290D01*
X293688Y305137D01*
X293947Y304907D01*
X294050Y304600D01*
G01X298792Y299243D02*
X298947Y299013D01*
X299050Y298745D01*
Y298438D01*
X298895Y298093D01*
X298637Y297825D01*
X298327Y297633D01*
X297810Y297480D01*
X297345Y297442D01*
X296880Y297518D01*
X296570Y297633D01*
X296260Y297863D01*
X296053Y298132D01*
X295950Y298400D01*
Y298668D01*
X296053Y298937D01*
X296208Y299167D01*
X296415Y299358D01*
G01Y300657D02*
X296157Y300887D01*
X296002Y301155D01*
X295950Y301500D01*
X296053Y301845D01*
X296260Y302113D01*
X296622Y302305D01*
X297035Y302343D01*
X297448Y302267D01*
X297707Y302075D01*
X297913Y301807D01*
X297965Y301538D01*
X297913Y301270D01*
X297707Y300925D01*
X299050Y301040D01*
Y302075D01*
G01X295950Y304600D02*
X296002Y304868D01*
X296157Y305175D01*
X296415Y305367D01*
X296777Y305443D01*
X297138Y305367D01*
X297448Y305137D01*
X297603Y304792D01*
Y304408D01*
X297707Y304178D01*
X297965Y303987D01*
X298327Y303910D01*
X298688Y304025D01*
X298947Y304293D01*
X299050Y304600D01*
X298947Y304907D01*
X298688Y305175D01*
X298327Y305290D01*
X297965Y305213D01*
X297707Y305022D01*
X297603Y304792D01*
Y304408D01*
X297448Y304063D01*
X297138Y303833D01*
X296777Y303757D01*
X296415Y303833D01*
X296157Y304025D01*
X296002Y304332D01*
X295950Y304600D01*
G01X304792Y298193D02*
X304947Y297963D01*
X305050Y297695D01*
Y297388D01*
X304895Y297043D01*
X304637Y296775D01*
X304327Y296583D01*
X303810Y296430D01*
X303345Y296392D01*
X302880Y296468D01*
X302570Y296583D01*
X302260Y296813D01*
X302053Y297082D01*
X301950Y297350D01*
Y297618D01*
X302053Y297887D01*
X302208Y298117D01*
X302415Y298308D01*
G01X304533Y299722D02*
X304843Y299952D01*
X304998Y300220D01*
X305050Y300527D01*
X304947Y300910D01*
X304688Y301178D01*
X304378Y301255D01*
X304068Y301217D01*
X303810Y301063D01*
X303293Y300297D01*
X302932Y299952D01*
X302415Y299722D01*
X301950Y299645D01*
Y301255D01*
G01Y303550D02*
X302002Y303818D01*
X302157Y304125D01*
X302415Y304317D01*
X302777Y304393D01*
X303138Y304317D01*
X303448Y304087D01*
X303603Y303742D01*
Y303358D01*
X303707Y303128D01*
X303965Y302937D01*
X304327Y302860D01*
X304688Y302975D01*
X304947Y303243D01*
X305050Y303550D01*
X304947Y303857D01*
X304688Y304125D01*
X304327Y304240D01*
X303965Y304163D01*
X303707Y303972D01*
X303603Y303742D01*
Y303358D01*
X303448Y303013D01*
X303138Y302783D01*
X302777Y302707D01*
X302415Y302783D01*
X302157Y302975D01*
X302002Y303282D01*
X301950Y303550D01*
G01X304533Y305922D02*
X304843Y306152D01*
X304998Y306420D01*
X305050Y306727D01*
X304947Y307110D01*
X304688Y307378D01*
X304378Y307455D01*
X304068Y307417D01*
X303810Y307263D01*
X303293Y306497D01*
X302932Y306152D01*
X302415Y305922D01*
X301950Y305845D01*
Y307455D01*
G01X305417Y338450D02*
Y341550D01*
X304458D01*
X304152Y341395D01*
X303960Y341188D01*
X303883Y340775D01*
X303960Y340362D01*
X304190Y340103D01*
X304458Y339948D01*
X305417D01*
G01X304458D02*
X303883Y338450D01*
G01X301550D02*
Y341550D01*
X302010Y340930D01*
G01Y338450D02*
X301090D01*
G01X299293Y338915D02*
X299063Y338657D01*
X298795Y338502D01*
X298450Y338450D01*
X298105Y338553D01*
X297837Y338760D01*
X297645Y339122D01*
X297607Y339535D01*
X297683Y339948D01*
X297875Y340207D01*
X298143Y340413D01*
X298412Y340465D01*
X298680Y340413D01*
X299025Y340207D01*
X298910Y341550D01*
X297875D01*
G01X294890Y338450D02*
Y341550D01*
X296308Y339328D01*
X294392D01*
G01X305417Y342450D02*
Y345550D01*
X304458D01*
X304152Y345395D01*
X303960Y345188D01*
X303883Y344775D01*
X303960Y344362D01*
X304190Y344103D01*
X304458Y343948D01*
X305417D01*
G01X304458D02*
X303883Y342450D01*
G01X301550D02*
Y345550D01*
X302010Y344930D01*
G01Y342450D02*
X301090D01*
G01X299293Y342915D02*
X299063Y342657D01*
X298795Y342502D01*
X298450Y342450D01*
X298105Y342553D01*
X297837Y342760D01*
X297645Y343122D01*
X297607Y343535D01*
X297683Y343948D01*
X297875Y344207D01*
X298143Y344413D01*
X298412Y344465D01*
X298680Y344413D01*
X299025Y344207D01*
X298910Y345550D01*
X297875D01*
G01X295350Y342450D02*
Y345550D01*
X295810Y344930D01*
G01Y342450D02*
X294890D01*
G01X312292Y65243D02*
X312447Y65013D01*
X312550Y64745D01*
Y64438D01*
X312395Y64093D01*
X312137Y63825D01*
X311827Y63633D01*
X311310Y63480D01*
X310845Y63442D01*
X310380Y63518D01*
X310070Y63633D01*
X309760Y63863D01*
X309553Y64132D01*
X309450Y64400D01*
Y64668D01*
X309553Y64937D01*
X309708Y65167D01*
X309915Y65358D01*
G01X310070Y66657D02*
X309708Y66887D01*
X309502Y67193D01*
X309450Y67538D01*
X309502Y67845D01*
X309760Y68152D01*
X310070Y68343D01*
X310380Y68382D01*
X310742Y68305D01*
X311000Y68037D01*
X311103Y67768D01*
Y67423D01*
G01Y67768D02*
X311258Y67998D01*
X311517Y68190D01*
X311827Y68267D01*
X312137Y68190D01*
X312395Y67998D01*
X312550Y67653D01*
X312498Y67308D01*
X312292Y66963D01*
G01X310742Y69872D02*
X311103Y70140D01*
X311310Y70370D01*
X311413Y70677D01*
X311310Y70945D01*
X311103Y71137D01*
X310793Y71290D01*
X310432Y71328D01*
X310122Y71290D01*
X309812Y71137D01*
X309553Y70907D01*
X309450Y70638D01*
X309553Y70332D01*
X309863Y70063D01*
X310328Y69910D01*
X310845Y69872D01*
X311517Y69948D01*
X311878Y70063D01*
X312240Y70255D01*
X312498Y70523D01*
X312550Y70792D01*
X312447Y71060D01*
X312188Y71252D01*
G01X316757Y202292D02*
X316987Y202447D01*
X317255Y202550D01*
X317562D01*
X317907Y202395D01*
X318175Y202137D01*
X318367Y201827D01*
X318520Y201310D01*
X318558Y200845D01*
X318482Y200380D01*
X318367Y200070D01*
X318137Y199760D01*
X317868Y199553D01*
X317600Y199450D01*
X317332D01*
X317063Y199553D01*
X316833Y199708D01*
X316642Y199915D01*
G01X315228Y200742D02*
X314960Y201103D01*
X314730Y201310D01*
X314423Y201413D01*
X314155Y201310D01*
X313963Y201103D01*
X313810Y200793D01*
X313772Y200432D01*
X313810Y200122D01*
X313963Y199812D01*
X314193Y199553D01*
X314462Y199450D01*
X314768Y199553D01*
X315037Y199863D01*
X315190Y200328D01*
X315228Y200845D01*
X315152Y201517D01*
X315037Y201878D01*
X314845Y202240D01*
X314577Y202498D01*
X314308Y202550D01*
X314040Y202447D01*
X313848Y202188D01*
G01X312243Y199915D02*
X312013Y199657D01*
X311745Y199502D01*
X311400Y199450D01*
X311055Y199553D01*
X310787Y199760D01*
X310595Y200122D01*
X310557Y200535D01*
X310633Y200948D01*
X310825Y201207D01*
X311093Y201413D01*
X311362Y201465D01*
X311630Y201413D01*
X311975Y201207D01*
X311860Y202550D01*
X310825D01*
G01X317757Y195792D02*
X317987Y195947D01*
X318255Y196050D01*
X318562D01*
X318907Y195895D01*
X319175Y195637D01*
X319367Y195327D01*
X319520Y194810D01*
X319558Y194345D01*
X319482Y193880D01*
X319367Y193570D01*
X319137Y193260D01*
X318868Y193053D01*
X318600Y192950D01*
X318332D01*
X318063Y193053D01*
X317833Y193208D01*
X317642Y193415D01*
G01X316228Y194242D02*
X315960Y194603D01*
X315730Y194810D01*
X315423Y194913D01*
X315155Y194810D01*
X314963Y194603D01*
X314810Y194293D01*
X314772Y193932D01*
X314810Y193622D01*
X314963Y193312D01*
X315193Y193053D01*
X315462Y192950D01*
X315768Y193053D01*
X316037Y193363D01*
X316190Y193828D01*
X316228Y194345D01*
X316152Y195017D01*
X316037Y195378D01*
X315845Y195740D01*
X315577Y195998D01*
X315308Y196050D01*
X315040Y195947D01*
X314848Y195688D01*
G01X311940Y192950D02*
Y196050D01*
X313358Y193828D01*
X311442D01*
G01X316757Y207292D02*
X316987Y207447D01*
X317255Y207550D01*
X317562D01*
X317907Y207395D01*
X318175Y207137D01*
X318367Y206827D01*
X318520Y206310D01*
X318558Y205845D01*
X318482Y205380D01*
X318367Y205070D01*
X318137Y204760D01*
X317868Y204553D01*
X317600Y204450D01*
X317332D01*
X317063Y204553D01*
X316833Y204708D01*
X316642Y204915D01*
G01X315228Y205742D02*
X314960Y206103D01*
X314730Y206310D01*
X314423Y206413D01*
X314155Y206310D01*
X313963Y206103D01*
X313810Y205793D01*
X313772Y205432D01*
X313810Y205122D01*
X313963Y204812D01*
X314193Y204553D01*
X314462Y204450D01*
X314768Y204553D01*
X315037Y204863D01*
X315190Y205328D01*
X315228Y205845D01*
X315152Y206517D01*
X315037Y206878D01*
X314845Y207240D01*
X314577Y207498D01*
X314308Y207550D01*
X314040Y207447D01*
X313848Y207188D01*
G01X312128Y205742D02*
X311860Y206103D01*
X311630Y206310D01*
X311323Y206413D01*
X311055Y206310D01*
X310863Y206103D01*
X310710Y205793D01*
X310672Y205432D01*
X310710Y205122D01*
X310863Y204812D01*
X311093Y204553D01*
X311362Y204450D01*
X311668Y204553D01*
X311937Y204863D01*
X312090Y205328D01*
X312128Y205845D01*
X312052Y206517D01*
X311937Y206878D01*
X311745Y207240D01*
X311477Y207498D01*
X311208Y207550D01*
X310940Y207447D01*
X310748Y207188D01*
G01X330867Y214950D02*
Y218050D01*
X329908D01*
X329602Y217895D01*
X329410Y217688D01*
X329333Y217275D01*
X329410Y216862D01*
X329640Y216603D01*
X329908Y216448D01*
X330867D01*
G01X329908D02*
X329333Y214950D01*
G01X327077D02*
X327000Y215622D01*
X326885Y216190D01*
X326732Y216707D01*
X326540Y217275D01*
X326233Y218050D01*
X327767D01*
G01X323977Y214950D02*
X323900Y215622D01*
X323785Y216190D01*
X323632Y216707D01*
X323440Y217275D01*
X323133Y218050D01*
X324667D01*
G01X312007Y213333D02*
X311847Y213583D01*
X311660Y213708D01*
X311447Y213750D01*
X311180Y213667D01*
X310993Y213458D01*
X310940Y213208D01*
X310967Y212958D01*
X311073Y212750D01*
X311607Y212333D01*
X311847Y212042D01*
X312007Y211625D01*
X312060Y211250D01*
X310940D01*
G01X314450Y216450D02*
X314502Y216143D01*
X314708Y215875D01*
X315018Y215645D01*
X315380Y215492D01*
X315793Y215415D01*
X316207D01*
X316620Y215492D01*
X316982Y215645D01*
X317292Y215875D01*
X317498Y216143D01*
X317550Y216450D01*
X317498Y216757D01*
X317292Y217025D01*
X316982Y217255D01*
X316620Y217408D01*
X316207Y217485D01*
X315793D01*
X315380Y217408D01*
X315018Y217255D01*
X314708Y217025D01*
X314502Y216757D01*
X314450Y216450D01*
G01X315277Y216757D02*
X314450Y217217D01*
G01X317033Y218822D02*
X317343Y219052D01*
X317498Y219320D01*
X317550Y219627D01*
X317447Y220010D01*
X317188Y220278D01*
X316878Y220355D01*
X316568Y220317D01*
X316310Y220163D01*
X315793Y219397D01*
X315432Y219052D01*
X314915Y218822D01*
X314450Y218745D01*
Y220355D01*
G01X310792Y239743D02*
X310947Y239513D01*
X311050Y239245D01*
Y238938D01*
X310895Y238593D01*
X310637Y238325D01*
X310327Y238133D01*
X309810Y237980D01*
X309345Y237942D01*
X308880Y238018D01*
X308570Y238133D01*
X308260Y238363D01*
X308053Y238632D01*
X307950Y238900D01*
Y239168D01*
X308053Y239437D01*
X308208Y239667D01*
X308415Y239858D01*
G01X307950Y241923D02*
X308622Y242000D01*
X309190Y242115D01*
X309707Y242268D01*
X310275Y242460D01*
X311050Y242767D01*
Y241233D01*
G01Y245100D02*
X310947Y244793D01*
X310688Y244563D01*
X310378Y244410D01*
X309965Y244295D01*
X309500Y244257D01*
X309035Y244295D01*
X308622Y244410D01*
X308312Y244563D01*
X308053Y244793D01*
X307950Y245100D01*
X308053Y245407D01*
X308312Y245637D01*
X308622Y245790D01*
X309035Y245905D01*
X309500Y245943D01*
X309965Y245905D01*
X310378Y245790D01*
X310688Y245637D01*
X310947Y245407D01*
X311050Y245100D01*
G01X316450Y238133D02*
X319550D01*
Y239092D01*
X319395Y239398D01*
X319188Y239590D01*
X318775Y239667D01*
X318362Y239590D01*
X318103Y239360D01*
X317948Y239092D01*
Y238133D01*
G01Y239092D02*
X316450Y239667D01*
G01Y242460D02*
X319550D01*
X317328Y241042D01*
Y242958D01*
G01X316450Y245560D02*
X319550D01*
X317328Y244142D01*
Y246058D01*
G01X312450Y238083D02*
X315550D01*
Y239042D01*
X315395Y239348D01*
X315188Y239540D01*
X314775Y239617D01*
X314362Y239540D01*
X314103Y239310D01*
X313948Y239042D01*
Y238083D01*
G01Y239042D02*
X312450Y239617D01*
G01X313070Y241107D02*
X312708Y241337D01*
X312502Y241643D01*
X312450Y241988D01*
X312502Y242295D01*
X312760Y242602D01*
X313070Y242793D01*
X313380Y242832D01*
X313742Y242755D01*
X314000Y242487D01*
X314103Y242218D01*
Y241873D01*
G01Y242218D02*
X314258Y242448D01*
X314517Y242640D01*
X314827Y242717D01*
X315137Y242640D01*
X315395Y242448D01*
X315550Y242103D01*
X315498Y241758D01*
X315292Y241413D01*
G01X312915Y244207D02*
X312657Y244437D01*
X312502Y244705D01*
X312450Y245050D01*
X312553Y245395D01*
X312760Y245663D01*
X313122Y245855D01*
X313535Y245893D01*
X313948Y245817D01*
X314207Y245625D01*
X314413Y245357D01*
X314465Y245088D01*
X314413Y244820D01*
X314207Y244475D01*
X315550Y244590D01*
Y245625D01*
G01X312450Y248073D02*
X313122Y248150D01*
X313690Y248265D01*
X314207Y248418D01*
X314775Y248610D01*
X315550Y248917D01*
Y247383D01*
G01X320450Y239450D02*
X320502Y239143D01*
X320708Y238875D01*
X321018Y238645D01*
X321380Y238492D01*
X321793Y238415D01*
X322207D01*
X322620Y238492D01*
X322982Y238645D01*
X323292Y238875D01*
X323498Y239143D01*
X323550Y239450D01*
X323498Y239757D01*
X323292Y240025D01*
X322982Y240255D01*
X322620Y240408D01*
X322207Y240485D01*
X321793D01*
X321380Y240408D01*
X321018Y240255D01*
X320708Y240025D01*
X320502Y239757D01*
X320450Y239450D01*
G01X321277Y239757D02*
X320450Y240217D01*
G01X321070Y241707D02*
X320708Y241937D01*
X320502Y242243D01*
X320450Y242588D01*
X320502Y242895D01*
X320760Y243202D01*
X321070Y243393D01*
X321380Y243432D01*
X321742Y243355D01*
X322000Y243087D01*
X322103Y242818D01*
Y242473D01*
G01Y242818D02*
X322258Y243048D01*
X322517Y243240D01*
X322827Y243317D01*
X323137Y243240D01*
X323395Y243048D01*
X323550Y242703D01*
X323498Y242358D01*
X323292Y242013D01*
G01X310792Y298693D02*
X310947Y298463D01*
X311050Y298195D01*
Y297888D01*
X310895Y297543D01*
X310637Y297275D01*
X310327Y297083D01*
X309810Y296930D01*
X309345Y296892D01*
X308880Y296968D01*
X308570Y297083D01*
X308260Y297313D01*
X308053Y297582D01*
X307950Y297850D01*
Y298118D01*
X308053Y298387D01*
X308208Y298617D01*
X308415Y298808D01*
G01X310533Y300222D02*
X310843Y300452D01*
X310998Y300720D01*
X311050Y301027D01*
X310947Y301410D01*
X310688Y301678D01*
X310378Y301755D01*
X310068Y301717D01*
X309810Y301563D01*
X309293Y300797D01*
X308932Y300452D01*
X308415Y300222D01*
X307950Y300145D01*
Y301755D01*
G01Y304050D02*
X308002Y304318D01*
X308157Y304625D01*
X308415Y304817D01*
X308777Y304893D01*
X309138Y304817D01*
X309448Y304587D01*
X309603Y304242D01*
Y303858D01*
X309707Y303628D01*
X309965Y303437D01*
X310327Y303360D01*
X310688Y303475D01*
X310947Y303743D01*
X311050Y304050D01*
X310947Y304357D01*
X310688Y304625D01*
X310327Y304740D01*
X309965Y304663D01*
X309707Y304472D01*
X309603Y304242D01*
Y303858D01*
X309448Y303513D01*
X309138Y303283D01*
X308777Y303207D01*
X308415Y303283D01*
X308157Y303475D01*
X308002Y303782D01*
X307950Y304050D01*
G01X308570Y306307D02*
X308208Y306537D01*
X308002Y306843D01*
X307950Y307188D01*
X308002Y307495D01*
X308260Y307802D01*
X308570Y307993D01*
X308880Y308032D01*
X309242Y307955D01*
X309500Y307687D01*
X309603Y307418D01*
Y307073D01*
G01Y307418D02*
X309758Y307648D01*
X310017Y307840D01*
X310327Y307917D01*
X310637Y307840D01*
X310895Y307648D01*
X311050Y307303D01*
X310998Y306958D01*
X310792Y306613D01*
G01X319050Y297683D02*
X315950D01*
Y299217D01*
G01X316570Y300707D02*
X316208Y300937D01*
X316002Y301243D01*
X315950Y301588D01*
X316002Y301895D01*
X316260Y302202D01*
X316570Y302393D01*
X316880Y302432D01*
X317242Y302355D01*
X317500Y302087D01*
X317603Y301818D01*
Y301473D01*
G01Y301818D02*
X317758Y302048D01*
X318017Y302240D01*
X318327Y302317D01*
X318637Y302240D01*
X318895Y302048D01*
X319050Y301703D01*
X318998Y301358D01*
X318792Y301013D01*
G01X332417Y314450D02*
Y317550D01*
X331458D01*
X331152Y317395D01*
X330960Y317188D01*
X330883Y316775D01*
X330960Y316362D01*
X331190Y316103D01*
X331458Y315948D01*
X332417D01*
G01X331458D02*
X330883Y314450D01*
G01X328550D02*
Y317550D01*
X329010Y316930D01*
G01Y314450D02*
X328090D01*
G01X326293Y314915D02*
X326063Y314657D01*
X325795Y314502D01*
X325450Y314450D01*
X325105Y314553D01*
X324837Y314760D01*
X324645Y315122D01*
X324607Y315535D01*
X324683Y315948D01*
X324875Y316207D01*
X325143Y316413D01*
X325412Y316465D01*
X325680Y316413D01*
X326025Y316207D01*
X325910Y317550D01*
X324875D01*
G01X323078Y317033D02*
X322848Y317343D01*
X322580Y317498D01*
X322273Y317550D01*
X321890Y317447D01*
X321622Y317188D01*
X321545Y316878D01*
X321583Y316568D01*
X321737Y316310D01*
X322503Y315793D01*
X322848Y315432D01*
X323078Y314915D01*
X323155Y314450D01*
X321545D01*
G01X332417Y310450D02*
Y313550D01*
X331458D01*
X331152Y313395D01*
X330960Y313188D01*
X330883Y312775D01*
X330960Y312362D01*
X331190Y312103D01*
X331458Y311948D01*
X332417D01*
G01X331458D02*
X330883Y310450D01*
G01X328550D02*
Y313550D01*
X329010Y312930D01*
G01Y310450D02*
X328090D01*
G01X324990D02*
Y313550D01*
X326408Y311328D01*
X324492D01*
G01X323002Y310812D02*
X322733Y310553D01*
X322427Y310450D01*
X322120Y310553D01*
X321852Y310863D01*
X321660Y311328D01*
X321583Y311793D01*
Y312362D01*
X321660Y312827D01*
X321852Y313240D01*
X322082Y313447D01*
X322350Y313550D01*
X322657Y313447D01*
X322887Y313240D01*
X323040Y312930D01*
X323117Y312517D01*
X323040Y312155D01*
X322848Y311793D01*
X322618Y311587D01*
X322350Y311535D01*
X322043Y311638D01*
X321813Y311897D01*
X321583Y312362D01*
G01X330417Y350450D02*
Y353550D01*
X329458D01*
X329152Y353395D01*
X328960Y353188D01*
X328883Y352775D01*
X328960Y352362D01*
X329190Y352103D01*
X329458Y351948D01*
X330417D01*
G01X329458D02*
X328883Y350450D01*
G01X326550D02*
Y353550D01*
X327010Y352930D01*
G01Y350450D02*
X326090D01*
G01X324293Y350915D02*
X324063Y350657D01*
X323795Y350502D01*
X323450Y350450D01*
X323105Y350553D01*
X322837Y350760D01*
X322645Y351122D01*
X322607Y351535D01*
X322683Y351948D01*
X322875Y352207D01*
X323143Y352413D01*
X323412Y352465D01*
X323680Y352413D01*
X324025Y352207D01*
X323910Y353550D01*
X322875D01*
G01X321193Y351070D02*
X320963Y350708D01*
X320657Y350502D01*
X320312Y350450D01*
X320005Y350502D01*
X319698Y350760D01*
X319507Y351070D01*
X319468Y351380D01*
X319545Y351742D01*
X319813Y352000D01*
X320082Y352103D01*
X320427D01*
G01X320082D02*
X319852Y352258D01*
X319660Y352517D01*
X319583Y352827D01*
X319660Y353137D01*
X319852Y353395D01*
X320197Y353550D01*
X320542Y353498D01*
X320887Y353292D01*
G01X330417Y354950D02*
Y358050D01*
X329458D01*
X329152Y357895D01*
X328960Y357688D01*
X328883Y357275D01*
X328960Y356862D01*
X329190Y356603D01*
X329458Y356448D01*
X330417D01*
G01X329458D02*
X328883Y354950D01*
G01X326550D02*
Y358050D01*
X327010Y357430D01*
G01Y354950D02*
X326090D01*
G01X324293Y355415D02*
X324063Y355157D01*
X323795Y355002D01*
X323450Y354950D01*
X323105Y355053D01*
X322837Y355260D01*
X322645Y355622D01*
X322607Y356035D01*
X322683Y356448D01*
X322875Y356707D01*
X323143Y356913D01*
X323412Y356965D01*
X323680Y356913D01*
X324025Y356707D01*
X323910Y358050D01*
X322875D01*
G01X320350D02*
X320657Y357947D01*
X320887Y357688D01*
X321040Y357378D01*
X321155Y356965D01*
X321193Y356500D01*
X321155Y356035D01*
X321040Y355622D01*
X320887Y355312D01*
X320657Y355053D01*
X320350Y354950D01*
X320043Y355053D01*
X319813Y355312D01*
X319660Y355622D01*
X319545Y356035D01*
X319507Y356500D01*
X319545Y356965D01*
X319660Y357378D01*
X319813Y357688D01*
X320043Y357947D01*
X320350Y358050D01*
G01X330367Y366950D02*
Y370050D01*
X329408D01*
X329102Y369895D01*
X328910Y369688D01*
X328833Y369275D01*
X328910Y368862D01*
X329140Y368603D01*
X329408Y368448D01*
X330367D01*
G01X329408D02*
X328833Y366950D01*
G01X327228Y368242D02*
X326960Y368603D01*
X326730Y368810D01*
X326423Y368913D01*
X326155Y368810D01*
X325963Y368603D01*
X325810Y368293D01*
X325772Y367932D01*
X325810Y367622D01*
X325963Y367312D01*
X326193Y367053D01*
X326462Y366950D01*
X326768Y367053D01*
X327037Y367363D01*
X327190Y367828D01*
X327228Y368345D01*
X327152Y369017D01*
X327037Y369378D01*
X326845Y369740D01*
X326577Y369998D01*
X326308Y370050D01*
X326040Y369947D01*
X325848Y369688D01*
G01X323400Y370050D02*
X323707Y369947D01*
X323937Y369688D01*
X324090Y369378D01*
X324205Y368965D01*
X324243Y368500D01*
X324205Y368035D01*
X324090Y367622D01*
X323937Y367312D01*
X323707Y367053D01*
X323400Y366950D01*
X323093Y367053D01*
X322863Y367312D01*
X322710Y367622D01*
X322595Y368035D01*
X322557Y368500D01*
X322595Y368965D01*
X322710Y369378D01*
X322863Y369688D01*
X323093Y369947D01*
X323400Y370050D01*
G01X330417Y358950D02*
Y362050D01*
X329458D01*
X329152Y361895D01*
X328960Y361688D01*
X328883Y361275D01*
X328960Y360862D01*
X329190Y360603D01*
X329458Y360448D01*
X330417D01*
G01X329458D02*
X328883Y358950D01*
G01X326550D02*
Y362050D01*
X327010Y361430D01*
G01Y358950D02*
X326090D01*
G01X322990D02*
Y362050D01*
X324408Y359828D01*
X322492D01*
G01X321078Y360242D02*
X320810Y360603D01*
X320580Y360810D01*
X320273Y360913D01*
X320005Y360810D01*
X319813Y360603D01*
X319660Y360293D01*
X319622Y359932D01*
X319660Y359622D01*
X319813Y359312D01*
X320043Y359053D01*
X320312Y358950D01*
X320618Y359053D01*
X320887Y359363D01*
X321040Y359828D01*
X321078Y360345D01*
X321002Y361017D01*
X320887Y361378D01*
X320695Y361740D01*
X320427Y361998D01*
X320158Y362050D01*
X319890Y361947D01*
X319698Y361688D01*
G01X330417Y362950D02*
Y366050D01*
X329458D01*
X329152Y365895D01*
X328960Y365688D01*
X328883Y365275D01*
X328960Y364862D01*
X329190Y364603D01*
X329458Y364448D01*
X330417D01*
G01X329458D02*
X328883Y362950D01*
G01X326550D02*
Y366050D01*
X327010Y365430D01*
G01Y362950D02*
X326090D01*
G01X324293Y363415D02*
X324063Y363157D01*
X323795Y363002D01*
X323450Y362950D01*
X323105Y363053D01*
X322837Y363260D01*
X322645Y363622D01*
X322607Y364035D01*
X322683Y364448D01*
X322875Y364707D01*
X323143Y364913D01*
X323412Y364965D01*
X323680Y364913D01*
X324025Y364707D01*
X323910Y366050D01*
X322875D01*
G01X321193Y363415D02*
X320963Y363157D01*
X320695Y363002D01*
X320350Y362950D01*
X320005Y363053D01*
X319737Y363260D01*
X319545Y363622D01*
X319507Y364035D01*
X319583Y364448D01*
X319775Y364707D01*
X320043Y364913D01*
X320312Y364965D01*
X320580Y364913D01*
X320925Y364707D01*
X320810Y366050D01*
X319775D01*
G01X314292Y388243D02*
X314447Y388013D01*
X314550Y387745D01*
Y387438D01*
X314395Y387093D01*
X314137Y386825D01*
X313827Y386633D01*
X313310Y386480D01*
X312845Y386442D01*
X312380Y386518D01*
X312070Y386633D01*
X311760Y386863D01*
X311553Y387132D01*
X311450Y387400D01*
Y387668D01*
X311553Y387937D01*
X311708Y388167D01*
X311915Y388358D01*
G01Y389657D02*
X311657Y389887D01*
X311502Y390155D01*
X311450Y390500D01*
X311553Y390845D01*
X311760Y391113D01*
X312122Y391305D01*
X312535Y391343D01*
X312948Y391267D01*
X313207Y391075D01*
X313413Y390807D01*
X313465Y390538D01*
X313413Y390270D01*
X313207Y389925D01*
X314550Y390040D01*
Y391075D01*
G01X311450Y393523D02*
X312122Y393600D01*
X312690Y393715D01*
X313207Y393868D01*
X313775Y394060D01*
X314550Y394367D01*
Y392833D01*
G01X310450Y374633D02*
X313550D01*
Y375592D01*
X313395Y375898D01*
X313188Y376090D01*
X312775Y376167D01*
X312362Y376090D01*
X312103Y375860D01*
X311948Y375592D01*
Y374633D01*
G01Y375592D02*
X310450Y376167D01*
G01X311070Y377657D02*
X310708Y377887D01*
X310502Y378193D01*
X310450Y378538D01*
X310502Y378845D01*
X310760Y379152D01*
X311070Y379343D01*
X311380Y379382D01*
X311742Y379305D01*
X312000Y379037D01*
X312103Y378768D01*
Y378423D01*
G01Y378768D02*
X312258Y378998D01*
X312517Y379190D01*
X312827Y379267D01*
X313137Y379190D01*
X313395Y378998D01*
X313550Y378653D01*
X313498Y378308D01*
X313292Y377963D01*
G01X310812Y380948D02*
X310553Y381217D01*
X310450Y381523D01*
X310553Y381830D01*
X310863Y382098D01*
X311328Y382290D01*
X311793Y382367D01*
X312362D01*
X312827Y382290D01*
X313240Y382098D01*
X313447Y381868D01*
X313550Y381600D01*
X313447Y381293D01*
X313240Y381063D01*
X312930Y380910D01*
X312517Y380833D01*
X312155Y380910D01*
X311793Y381102D01*
X311587Y381332D01*
X311535Y381600D01*
X311638Y381907D01*
X311897Y382137D01*
X312362Y382367D01*
G01X319257Y408292D02*
X319487Y408447D01*
X319755Y408550D01*
X320062D01*
X320407Y408395D01*
X320675Y408137D01*
X320867Y407827D01*
X321020Y407310D01*
X321058Y406845D01*
X320982Y406380D01*
X320867Y406070D01*
X320637Y405760D01*
X320368Y405553D01*
X320100Y405450D01*
X319832D01*
X319563Y405553D01*
X319333Y405708D01*
X319142Y405915D01*
G01X317843D02*
X317613Y405657D01*
X317345Y405502D01*
X317000Y405450D01*
X316655Y405553D01*
X316387Y405760D01*
X316195Y406122D01*
X316157Y406535D01*
X316233Y406948D01*
X316425Y407207D01*
X316693Y407413D01*
X316962Y407465D01*
X317230Y407413D01*
X317575Y407207D01*
X317460Y408550D01*
X316425D01*
G01X314628Y406742D02*
X314360Y407103D01*
X314130Y407310D01*
X313823Y407413D01*
X313555Y407310D01*
X313363Y407103D01*
X313210Y406793D01*
X313172Y406432D01*
X313210Y406122D01*
X313363Y405812D01*
X313593Y405553D01*
X313862Y405450D01*
X314168Y405553D01*
X314437Y405863D01*
X314590Y406328D01*
X314628Y406845D01*
X314552Y407517D01*
X314437Y407878D01*
X314245Y408240D01*
X313977Y408498D01*
X313708Y408550D01*
X313440Y408447D01*
X313248Y408188D01*
G01X337867Y228450D02*
Y231550D01*
X336908D01*
X336602Y231395D01*
X336410Y231188D01*
X336333Y230775D01*
X336410Y230362D01*
X336640Y230103D01*
X336908Y229948D01*
X337867D01*
G01X336908D02*
X336333Y228450D01*
G01X334077D02*
X334000Y229122D01*
X333885Y229690D01*
X333732Y230207D01*
X333540Y230775D01*
X333233Y231550D01*
X334767D01*
G01X331743Y228915D02*
X331513Y228657D01*
X331245Y228502D01*
X330900Y228450D01*
X330555Y228553D01*
X330287Y228760D01*
X330095Y229122D01*
X330057Y229535D01*
X330133Y229948D01*
X330325Y230207D01*
X330593Y230413D01*
X330862Y230465D01*
X331130Y230413D01*
X331475Y230207D01*
X331360Y231550D01*
X330325D01*
G01X336450Y248133D02*
X339550D01*
Y249092D01*
X339395Y249398D01*
X339188Y249590D01*
X338775Y249667D01*
X338362Y249590D01*
X338103Y249360D01*
X337948Y249092D01*
Y248133D01*
G01Y249092D02*
X336450Y249667D01*
G01Y252000D02*
X336502Y252268D01*
X336657Y252575D01*
X336915Y252767D01*
X337277Y252843D01*
X337638Y252767D01*
X337948Y252537D01*
X338103Y252192D01*
Y251808D01*
X338207Y251578D01*
X338465Y251387D01*
X338827Y251310D01*
X339188Y251425D01*
X339447Y251693D01*
X339550Y252000D01*
X339447Y252307D01*
X339188Y252575D01*
X338827Y252690D01*
X338465Y252613D01*
X338207Y252422D01*
X338103Y252192D01*
Y251808D01*
X337948Y251463D01*
X337638Y251233D01*
X337277Y251157D01*
X336915Y251233D01*
X336657Y251425D01*
X336502Y251732D01*
X336450Y252000D01*
G01X339550Y255100D02*
X339447Y254793D01*
X339188Y254563D01*
X338878Y254410D01*
X338465Y254295D01*
X338000Y254257D01*
X337535Y254295D01*
X337122Y254410D01*
X336812Y254563D01*
X336553Y254793D01*
X336450Y255100D01*
X336553Y255407D01*
X336812Y255637D01*
X337122Y255790D01*
X337535Y255905D01*
X338000Y255943D01*
X338465Y255905D01*
X338878Y255790D01*
X339188Y255637D01*
X339447Y255407D01*
X339550Y255100D01*
G01X330792Y283743D02*
X330947Y283513D01*
X331050Y283245D01*
Y282938D01*
X330895Y282593D01*
X330637Y282325D01*
X330327Y282133D01*
X329810Y281980D01*
X329345Y281942D01*
X328880Y282018D01*
X328570Y282133D01*
X328260Y282363D01*
X328053Y282632D01*
X327950Y282900D01*
Y283168D01*
X328053Y283437D01*
X328208Y283667D01*
X328415Y283858D01*
G01X329242Y285272D02*
X329603Y285540D01*
X329810Y285770D01*
X329913Y286077D01*
X329810Y286345D01*
X329603Y286537D01*
X329293Y286690D01*
X328932Y286728D01*
X328622Y286690D01*
X328312Y286537D01*
X328053Y286307D01*
X327950Y286038D01*
X328053Y285732D01*
X328363Y285463D01*
X328828Y285310D01*
X329345Y285272D01*
X330017Y285348D01*
X330378Y285463D01*
X330740Y285655D01*
X330998Y285923D01*
X331050Y286192D01*
X330947Y286460D01*
X330688Y286652D01*
G01X330533Y288372D02*
X330843Y288602D01*
X330998Y288870D01*
X331050Y289177D01*
X330947Y289560D01*
X330688Y289828D01*
X330378Y289905D01*
X330068Y289867D01*
X329810Y289713D01*
X329293Y288947D01*
X328932Y288602D01*
X328415Y288372D01*
X327950Y288295D01*
Y289905D01*
G01X341950Y269083D02*
X345050D01*
Y270042D01*
X344895Y270348D01*
X344688Y270540D01*
X344275Y270617D01*
X343862Y270540D01*
X343603Y270310D01*
X343448Y270042D01*
Y269083D01*
G01Y270042D02*
X341950Y270617D01*
G01X342570Y272107D02*
X342208Y272337D01*
X342002Y272643D01*
X341950Y272988D01*
X342002Y273295D01*
X342260Y273602D01*
X342570Y273793D01*
X342880Y273832D01*
X343242Y273755D01*
X343500Y273487D01*
X343603Y273218D01*
Y272873D01*
G01Y273218D02*
X343758Y273448D01*
X344017Y273640D01*
X344327Y273717D01*
X344637Y273640D01*
X344895Y273448D01*
X345050Y273103D01*
X344998Y272758D01*
X344792Y272413D01*
G01X342570Y275207D02*
X342208Y275437D01*
X342002Y275743D01*
X341950Y276088D01*
X342002Y276395D01*
X342260Y276702D01*
X342570Y276893D01*
X342880Y276932D01*
X343242Y276855D01*
X343500Y276587D01*
X343603Y276318D01*
Y275973D01*
G01Y276318D02*
X343758Y276548D01*
X344017Y276740D01*
X344327Y276817D01*
X344637Y276740D01*
X344895Y276548D01*
X345050Y276203D01*
X344998Y275858D01*
X344792Y275513D01*
G01X345050Y279150D02*
X344947Y278843D01*
X344688Y278613D01*
X344378Y278460D01*
X343965Y278345D01*
X343500Y278307D01*
X343035Y278345D01*
X342622Y278460D01*
X342312Y278613D01*
X342053Y278843D01*
X341950Y279150D01*
X342053Y279457D01*
X342312Y279687D01*
X342622Y279840D01*
X343035Y279955D01*
X343500Y279993D01*
X343965Y279955D01*
X344378Y279840D01*
X344688Y279687D01*
X344947Y279457D01*
X345050Y279150D01*
G01X333450Y269083D02*
X336550D01*
Y270042D01*
X336395Y270348D01*
X336188Y270540D01*
X335775Y270617D01*
X335362Y270540D01*
X335103Y270310D01*
X334948Y270042D01*
Y269083D01*
G01Y270042D02*
X333450Y270617D01*
G01X334070Y272107D02*
X333708Y272337D01*
X333502Y272643D01*
X333450Y272988D01*
X333502Y273295D01*
X333760Y273602D01*
X334070Y273793D01*
X334380Y273832D01*
X334742Y273755D01*
X335000Y273487D01*
X335103Y273218D01*
Y272873D01*
G01Y273218D02*
X335258Y273448D01*
X335517Y273640D01*
X335827Y273717D01*
X336137Y273640D01*
X336395Y273448D01*
X336550Y273103D01*
X336498Y272758D01*
X336292Y272413D01*
G01X334742Y275322D02*
X335103Y275590D01*
X335310Y275820D01*
X335413Y276127D01*
X335310Y276395D01*
X335103Y276587D01*
X334793Y276740D01*
X334432Y276778D01*
X334122Y276740D01*
X333812Y276587D01*
X333553Y276357D01*
X333450Y276088D01*
X333553Y275782D01*
X333863Y275513D01*
X334328Y275360D01*
X334845Y275322D01*
X335517Y275398D01*
X335878Y275513D01*
X336240Y275705D01*
X336498Y275973D01*
X336550Y276242D01*
X336447Y276510D01*
X336188Y276702D01*
G01X334070Y278307D02*
X333708Y278537D01*
X333502Y278843D01*
X333450Y279188D01*
X333502Y279495D01*
X333760Y279802D01*
X334070Y279993D01*
X334380Y280032D01*
X334742Y279955D01*
X335000Y279687D01*
X335103Y279418D01*
Y279073D01*
G01Y279418D02*
X335258Y279648D01*
X335517Y279840D01*
X335827Y279917D01*
X336137Y279840D01*
X336395Y279648D01*
X336550Y279303D01*
X336498Y278958D01*
X336292Y278613D01*
G01X337450Y269083D02*
X340550D01*
Y270042D01*
X340395Y270348D01*
X340188Y270540D01*
X339775Y270617D01*
X339362Y270540D01*
X339103Y270310D01*
X338948Y270042D01*
Y269083D01*
G01Y270042D02*
X337450Y270617D01*
G01X338070Y272107D02*
X337708Y272337D01*
X337502Y272643D01*
X337450Y272988D01*
X337502Y273295D01*
X337760Y273602D01*
X338070Y273793D01*
X338380Y273832D01*
X338742Y273755D01*
X339000Y273487D01*
X339103Y273218D01*
Y272873D01*
G01Y273218D02*
X339258Y273448D01*
X339517Y273640D01*
X339827Y273717D01*
X340137Y273640D01*
X340395Y273448D01*
X340550Y273103D01*
X340498Y272758D01*
X340292Y272413D01*
G01X337450Y276510D02*
X340550D01*
X338328Y275092D01*
Y277008D01*
G01X340033Y278422D02*
X340343Y278652D01*
X340498Y278920D01*
X340550Y279227D01*
X340447Y279610D01*
X340188Y279878D01*
X339878Y279955D01*
X339568Y279917D01*
X339310Y279763D01*
X338793Y278997D01*
X338432Y278652D01*
X337915Y278422D01*
X337450Y278345D01*
Y279955D01*
G01X337405Y386863D02*
X337098Y386605D01*
X336753Y386450D01*
X336447D01*
X336140Y386605D01*
X335910Y386863D01*
X335795Y387225D01*
X335872Y387587D01*
X336063Y387897D01*
X336408Y388103D01*
X336868Y388207D01*
X337137Y388413D01*
X337252Y388775D01*
X337175Y389137D01*
X336983Y389395D01*
X336715Y389550D01*
X336447D01*
X336178Y389447D01*
X335948Y389188D01*
G01X334267Y386450D02*
Y389550D01*
X333347D01*
X333040Y389395D01*
X332810Y389033D01*
X332733Y388620D01*
X332810Y388207D01*
X333002Y387897D01*
X333347Y387742D01*
X334267D01*
G01X331128Y389033D02*
X330898Y389343D01*
X330630Y389498D01*
X330323Y389550D01*
X329940Y389447D01*
X329672Y389188D01*
X329595Y388878D01*
X329633Y388568D01*
X329787Y388310D01*
X330553Y387793D01*
X330898Y387432D01*
X331128Y386915D01*
X331205Y386450D01*
X329595D01*
G01X340367Y402950D02*
Y406050D01*
X339408D01*
X339102Y405895D01*
X338910Y405688D01*
X338833Y405275D01*
X338910Y404862D01*
X339140Y404603D01*
X339408Y404448D01*
X340367D01*
G01X339408D02*
X338833Y402950D01*
G01X337343Y403570D02*
X337113Y403208D01*
X336807Y403002D01*
X336462Y402950D01*
X336155Y403002D01*
X335848Y403260D01*
X335657Y403570D01*
X335618Y403880D01*
X335695Y404242D01*
X335963Y404500D01*
X336232Y404603D01*
X336577D01*
G01X336232D02*
X336002Y404758D01*
X335810Y405017D01*
X335733Y405327D01*
X335810Y405637D01*
X336002Y405895D01*
X336347Y406050D01*
X336692Y405998D01*
X337037Y405792D01*
G01X333477Y402950D02*
X333400Y403622D01*
X333285Y404190D01*
X333132Y404707D01*
X332940Y405275D01*
X332633Y406050D01*
X334167D01*
G01X353842Y116193D02*
X353997Y115963D01*
X354100Y115695D01*
Y115388D01*
X353945Y115043D01*
X353687Y114775D01*
X353377Y114583D01*
X352860Y114430D01*
X352395Y114392D01*
X351930Y114468D01*
X351620Y114583D01*
X351310Y114813D01*
X351103Y115082D01*
X351000Y115350D01*
Y115618D01*
X351103Y115887D01*
X351258Y116117D01*
X351465Y116308D01*
G01X351000Y118450D02*
X354100D01*
X353480Y117990D01*
G01X351000D02*
Y118910D01*
G01X351620Y120707D02*
X351258Y120937D01*
X351052Y121243D01*
X351000Y121588D01*
X351052Y121895D01*
X351310Y122202D01*
X351620Y122393D01*
X351930Y122432D01*
X352292Y122355D01*
X352550Y122087D01*
X352653Y121818D01*
Y121473D01*
G01Y121818D02*
X352808Y122048D01*
X353067Y122240D01*
X353377Y122317D01*
X353687Y122240D01*
X353945Y122048D01*
X354100Y121703D01*
X354048Y121358D01*
X353842Y121013D01*
G01X352292Y123922D02*
X352653Y124190D01*
X352860Y124420D01*
X352963Y124727D01*
X352860Y124995D01*
X352653Y125187D01*
X352343Y125340D01*
X351982Y125378D01*
X351672Y125340D01*
X351362Y125187D01*
X351103Y124957D01*
X351000Y124688D01*
X351103Y124382D01*
X351413Y124113D01*
X351878Y123960D01*
X352395Y123922D01*
X353067Y123998D01*
X353428Y124113D01*
X353790Y124305D01*
X354048Y124573D01*
X354100Y124842D01*
X353997Y125110D01*
X353738Y125302D01*
G01X347292Y117193D02*
X347447Y116963D01*
X347550Y116695D01*
Y116388D01*
X347395Y116043D01*
X347137Y115775D01*
X346827Y115583D01*
X346310Y115430D01*
X345845Y115392D01*
X345380Y115468D01*
X345070Y115583D01*
X344760Y115813D01*
X344553Y116082D01*
X344450Y116350D01*
Y116618D01*
X344553Y116887D01*
X344708Y117117D01*
X344915Y117308D01*
G01X344450Y119450D02*
X347550D01*
X346930Y118990D01*
G01X344450D02*
Y119910D01*
G01Y123010D02*
X347550D01*
X345328Y121592D01*
Y123508D01*
G01X345070Y124807D02*
X344708Y125037D01*
X344502Y125343D01*
X344450Y125688D01*
X344502Y125995D01*
X344760Y126302D01*
X345070Y126493D01*
X345380Y126532D01*
X345742Y126455D01*
X346000Y126187D01*
X346103Y125918D01*
Y125573D01*
G01Y125918D02*
X346258Y126148D01*
X346517Y126340D01*
X346827Y126417D01*
X347137Y126340D01*
X347395Y126148D01*
X347550Y125803D01*
X347498Y125458D01*
X347292Y125113D01*
G01X345792Y177243D02*
X345947Y177013D01*
X346050Y176745D01*
Y176438D01*
X345895Y176093D01*
X345637Y175825D01*
X345327Y175633D01*
X344810Y175480D01*
X344345Y175442D01*
X343880Y175518D01*
X343570Y175633D01*
X343260Y175863D01*
X343053Y176132D01*
X342950Y176400D01*
Y176668D01*
X343053Y176937D01*
X343208Y177167D01*
X343415Y177358D01*
G01X344242Y178772D02*
X344603Y179040D01*
X344810Y179270D01*
X344913Y179577D01*
X344810Y179845D01*
X344603Y180037D01*
X344293Y180190D01*
X343932Y180228D01*
X343622Y180190D01*
X343312Y180037D01*
X343053Y179807D01*
X342950Y179538D01*
X343053Y179232D01*
X343363Y178963D01*
X343828Y178810D01*
X344345Y178772D01*
X345017Y178848D01*
X345378Y178963D01*
X345740Y179155D01*
X345998Y179423D01*
X346050Y179692D01*
X345947Y179960D01*
X345688Y180152D01*
G01X342950Y182523D02*
X343622Y182600D01*
X344190Y182715D01*
X344707Y182868D01*
X345275Y183060D01*
X346050Y183367D01*
Y181833D01*
G01X363917Y170950D02*
Y174050D01*
X362958D01*
X362652Y173895D01*
X362460Y173688D01*
X362383Y173275D01*
X362460Y172862D01*
X362690Y172603D01*
X362958Y172448D01*
X363917D01*
G01X362958D02*
X362383Y170950D01*
G01X360050D02*
Y174050D01*
X360510Y173430D01*
G01Y170950D02*
X359590D01*
G01X357602Y171312D02*
X357333Y171053D01*
X357027Y170950D01*
X356720Y171053D01*
X356452Y171363D01*
X356260Y171828D01*
X356183Y172293D01*
Y172862D01*
X356260Y173327D01*
X356452Y173740D01*
X356682Y173947D01*
X356950Y174050D01*
X357257Y173947D01*
X357487Y173740D01*
X357640Y173430D01*
X357717Y173017D01*
X357640Y172655D01*
X357448Y172293D01*
X357218Y172087D01*
X356950Y172035D01*
X356643Y172138D01*
X356413Y172397D01*
X356183Y172862D01*
G01X354578Y172242D02*
X354310Y172603D01*
X354080Y172810D01*
X353773Y172913D01*
X353505Y172810D01*
X353313Y172603D01*
X353160Y172293D01*
X353122Y171932D01*
X353160Y171622D01*
X353313Y171312D01*
X353543Y171053D01*
X353812Y170950D01*
X354118Y171053D01*
X354387Y171363D01*
X354540Y171828D01*
X354578Y172345D01*
X354502Y173017D01*
X354387Y173378D01*
X354195Y173740D01*
X353927Y173998D01*
X353658Y174050D01*
X353390Y173947D01*
X353198Y173688D01*
G01X363817Y197100D02*
Y200200D01*
X362858D01*
X362552Y200045D01*
X362360Y199838D01*
X362283Y199425D01*
X362360Y199012D01*
X362590Y198753D01*
X362858Y198598D01*
X363817D01*
G01X362858D02*
X362283Y197100D01*
G01X359950D02*
Y200200D01*
X360410Y199580D01*
G01Y197100D02*
X359490D01*
G01X356850Y200200D02*
X357157Y200097D01*
X357387Y199838D01*
X357540Y199528D01*
X357655Y199115D01*
X357693Y198650D01*
X357655Y198185D01*
X357540Y197772D01*
X357387Y197462D01*
X357157Y197203D01*
X356850Y197100D01*
X356543Y197203D01*
X356313Y197462D01*
X356160Y197772D01*
X356045Y198185D01*
X356007Y198650D01*
X356045Y199115D01*
X356160Y199528D01*
X356313Y199838D01*
X356543Y200097D01*
X356850Y200200D01*
G01X354478Y198392D02*
X354210Y198753D01*
X353980Y198960D01*
X353673Y199063D01*
X353405Y198960D01*
X353213Y198753D01*
X353060Y198443D01*
X353022Y198082D01*
X353060Y197772D01*
X353213Y197462D01*
X353443Y197203D01*
X353712Y197100D01*
X354018Y197203D01*
X354287Y197513D01*
X354440Y197978D01*
X354478Y198495D01*
X354402Y199167D01*
X354287Y199528D01*
X354095Y199890D01*
X353827Y200148D01*
X353558Y200200D01*
X353290Y200097D01*
X353098Y199838D01*
G01X363817Y201600D02*
Y204700D01*
X362858D01*
X362552Y204545D01*
X362360Y204338D01*
X362283Y203925D01*
X362360Y203512D01*
X362590Y203253D01*
X362858Y203098D01*
X363817D01*
G01X362858D02*
X362283Y201600D01*
G01X359950D02*
Y204700D01*
X360410Y204080D01*
G01Y201600D02*
X359490D01*
G01X356850Y204700D02*
X357157Y204597D01*
X357387Y204338D01*
X357540Y204028D01*
X357655Y203615D01*
X357693Y203150D01*
X357655Y202685D01*
X357540Y202272D01*
X357387Y201962D01*
X357157Y201703D01*
X356850Y201600D01*
X356543Y201703D01*
X356313Y201962D01*
X356160Y202272D01*
X356045Y202685D01*
X356007Y203150D01*
X356045Y203615D01*
X356160Y204028D01*
X356313Y204338D01*
X356543Y204597D01*
X356850Y204700D01*
G01X354593Y202065D02*
X354363Y201807D01*
X354095Y201652D01*
X353750Y201600D01*
X353405Y201703D01*
X353137Y201910D01*
X352945Y202272D01*
X352907Y202685D01*
X352983Y203098D01*
X353175Y203357D01*
X353443Y203563D01*
X353712Y203615D01*
X353980Y203563D01*
X354325Y203357D01*
X354210Y204700D01*
X353175D01*
G01X354867Y211950D02*
Y215050D01*
X353908D01*
X353602Y214895D01*
X353410Y214688D01*
X353333Y214275D01*
X353410Y213862D01*
X353640Y213603D01*
X353908Y213448D01*
X354867D01*
G01X353908D02*
X353333Y211950D01*
G01X351077D02*
X351000Y212622D01*
X350885Y213190D01*
X350732Y213707D01*
X350540Y214275D01*
X350233Y215050D01*
X351767D01*
G01X347440Y211950D02*
Y215050D01*
X348858Y212828D01*
X346942D01*
G01X354867Y207450D02*
Y210550D01*
X353908D01*
X353602Y210395D01*
X353410Y210188D01*
X353333Y209775D01*
X353410Y209362D01*
X353640Y209103D01*
X353908Y208948D01*
X354867D01*
G01X353908D02*
X353333Y207450D01*
G01X351077D02*
X351000Y208122D01*
X350885Y208690D01*
X350732Y209207D01*
X350540Y209775D01*
X350233Y210550D01*
X351767D01*
G01X348628Y208742D02*
X348360Y209103D01*
X348130Y209310D01*
X347823Y209413D01*
X347555Y209310D01*
X347363Y209103D01*
X347210Y208793D01*
X347172Y208432D01*
X347210Y208122D01*
X347363Y207812D01*
X347593Y207553D01*
X347862Y207450D01*
X348168Y207553D01*
X348437Y207863D01*
X348590Y208328D01*
X348628Y208845D01*
X348552Y209517D01*
X348437Y209878D01*
X348245Y210240D01*
X347977Y210498D01*
X347708Y210550D01*
X347440Y210447D01*
X347248Y210188D01*
G01X362807Y230292D02*
X363037Y230447D01*
X363305Y230550D01*
X363612D01*
X363957Y230395D01*
X364225Y230137D01*
X364417Y229827D01*
X364570Y229310D01*
X364608Y228845D01*
X364532Y228380D01*
X364417Y228070D01*
X364187Y227760D01*
X363918Y227553D01*
X363650Y227450D01*
X363382D01*
X363113Y227553D01*
X362883Y227708D01*
X362692Y227915D01*
G01X360550Y227450D02*
Y230550D01*
X361010Y229930D01*
G01Y227450D02*
X360090D01*
G01X358293Y227915D02*
X358063Y227657D01*
X357795Y227502D01*
X357450Y227450D01*
X357105Y227553D01*
X356837Y227760D01*
X356645Y228122D01*
X356607Y228535D01*
X356683Y228948D01*
X356875Y229207D01*
X357143Y229413D01*
X357412Y229465D01*
X357680Y229413D01*
X358025Y229207D01*
X357910Y230550D01*
X356875D01*
G01X354350Y227450D02*
X354082Y227502D01*
X353775Y227657D01*
X353583Y227915D01*
X353507Y228277D01*
X353583Y228638D01*
X353813Y228948D01*
X354158Y229103D01*
X354542D01*
X354772Y229207D01*
X354963Y229465D01*
X355040Y229827D01*
X354925Y230188D01*
X354657Y230447D01*
X354350Y230550D01*
X354043Y230447D01*
X353775Y230188D01*
X353660Y229827D01*
X353737Y229465D01*
X353928Y229207D01*
X354158Y229103D01*
X354542D01*
X354887Y228948D01*
X355117Y228638D01*
X355193Y228277D01*
X355117Y227915D01*
X354925Y227657D01*
X354618Y227502D01*
X354350Y227450D01*
G01X346450Y241083D02*
X349550D01*
Y242042D01*
X349395Y242348D01*
X349188Y242540D01*
X348775Y242617D01*
X348362Y242540D01*
X348103Y242310D01*
X347948Y242042D01*
Y241083D01*
G01Y242042D02*
X346450Y242617D01*
G01Y244950D02*
X349550D01*
X348930Y244490D01*
G01X346450D02*
Y245410D01*
G01X347742Y247322D02*
X348103Y247590D01*
X348310Y247820D01*
X348413Y248127D01*
X348310Y248395D01*
X348103Y248587D01*
X347793Y248740D01*
X347432Y248778D01*
X347122Y248740D01*
X346812Y248587D01*
X346553Y248357D01*
X346450Y248088D01*
X346553Y247782D01*
X346863Y247513D01*
X347328Y247360D01*
X347845Y247322D01*
X348517Y247398D01*
X348878Y247513D01*
X349240Y247705D01*
X349498Y247973D01*
X349550Y248242D01*
X349447Y248510D01*
X349188Y248702D01*
G01X346450Y251150D02*
X346502Y251418D01*
X346657Y251725D01*
X346915Y251917D01*
X347277Y251993D01*
X347638Y251917D01*
X347948Y251687D01*
X348103Y251342D01*
Y250958D01*
X348207Y250728D01*
X348465Y250537D01*
X348827Y250460D01*
X349188Y250575D01*
X349447Y250843D01*
X349550Y251150D01*
X349447Y251457D01*
X349188Y251725D01*
X348827Y251840D01*
X348465Y251763D01*
X348207Y251572D01*
X348103Y251342D01*
Y250958D01*
X347948Y250613D01*
X347638Y250383D01*
X347277Y250307D01*
X346915Y250383D01*
X346657Y250575D01*
X346502Y250882D01*
X346450Y251150D01*
G01Y269083D02*
X349550D01*
Y270042D01*
X349395Y270348D01*
X349188Y270540D01*
X348775Y270617D01*
X348362Y270540D01*
X348103Y270310D01*
X347948Y270042D01*
Y269083D01*
G01Y270042D02*
X346450Y270617D01*
G01X347070Y272107D02*
X346708Y272337D01*
X346502Y272643D01*
X346450Y272988D01*
X346502Y273295D01*
X346760Y273602D01*
X347070Y273793D01*
X347380Y273832D01*
X347742Y273755D01*
X348000Y273487D01*
X348103Y273218D01*
Y272873D01*
G01Y273218D02*
X348258Y273448D01*
X348517Y273640D01*
X348827Y273717D01*
X349137Y273640D01*
X349395Y273448D01*
X349550Y273103D01*
X349498Y272758D01*
X349292Y272413D01*
G01X346450Y276510D02*
X349550D01*
X347328Y275092D01*
Y277008D01*
G01X346450Y279150D02*
X349550D01*
X348930Y278690D01*
G01X346450D02*
Y279610D01*
G01X354917Y352950D02*
Y356050D01*
X353958D01*
X353652Y355895D01*
X353460Y355688D01*
X353383Y355275D01*
X353460Y354862D01*
X353690Y354603D01*
X353958Y354448D01*
X354917D01*
G01X353958D02*
X353383Y352950D01*
G01X351050D02*
Y356050D01*
X351510Y355430D01*
G01Y352950D02*
X350590D01*
G01X348602Y353312D02*
X348333Y353053D01*
X348027Y352950D01*
X347720Y353053D01*
X347452Y353363D01*
X347260Y353828D01*
X347183Y354293D01*
Y354862D01*
X347260Y355327D01*
X347452Y355740D01*
X347682Y355947D01*
X347950Y356050D01*
X348257Y355947D01*
X348487Y355740D01*
X348640Y355430D01*
X348717Y355017D01*
X348640Y354655D01*
X348448Y354293D01*
X348218Y354087D01*
X347950Y354035D01*
X347643Y354138D01*
X347413Y354397D01*
X347183Y354862D01*
G01X345578Y355533D02*
X345348Y355843D01*
X345080Y355998D01*
X344773Y356050D01*
X344390Y355947D01*
X344122Y355688D01*
X344045Y355378D01*
X344083Y355068D01*
X344237Y354810D01*
X345003Y354293D01*
X345348Y353932D01*
X345578Y353415D01*
X345655Y352950D01*
X344045D01*
G01X354917Y348450D02*
Y351550D01*
X353958D01*
X353652Y351395D01*
X353460Y351188D01*
X353383Y350775D01*
X353460Y350362D01*
X353690Y350103D01*
X353958Y349948D01*
X354917D01*
G01X353958D02*
X353383Y348450D01*
G01X351778Y351033D02*
X351548Y351343D01*
X351280Y351498D01*
X350973Y351550D01*
X350590Y351447D01*
X350322Y351188D01*
X350245Y350878D01*
X350283Y350568D01*
X350437Y350310D01*
X351203Y349793D01*
X351548Y349432D01*
X351778Y348915D01*
X351855Y348450D01*
X350245D01*
G01X347950Y351550D02*
X348257Y351447D01*
X348487Y351188D01*
X348640Y350878D01*
X348755Y350465D01*
X348793Y350000D01*
X348755Y349535D01*
X348640Y349122D01*
X348487Y348812D01*
X348257Y348553D01*
X347950Y348450D01*
X347643Y348553D01*
X347413Y348812D01*
X347260Y349122D01*
X347145Y349535D01*
X347107Y350000D01*
X347145Y350465D01*
X347260Y350878D01*
X347413Y351188D01*
X347643Y351447D01*
X347950Y351550D01*
G01X345578Y351033D02*
X345348Y351343D01*
X345080Y351498D01*
X344773Y351550D01*
X344390Y351447D01*
X344122Y351188D01*
X344045Y350878D01*
X344083Y350568D01*
X344237Y350310D01*
X345003Y349793D01*
X345348Y349432D01*
X345578Y348915D01*
X345655Y348450D01*
X344045D01*
G01X354917Y344450D02*
Y347550D01*
X353958D01*
X353652Y347395D01*
X353460Y347188D01*
X353383Y346775D01*
X353460Y346362D01*
X353690Y346103D01*
X353958Y345948D01*
X354917D01*
G01X353958D02*
X353383Y344450D01*
G01X351778Y347033D02*
X351548Y347343D01*
X351280Y347498D01*
X350973Y347550D01*
X350590Y347447D01*
X350322Y347188D01*
X350245Y346878D01*
X350283Y346568D01*
X350437Y346310D01*
X351203Y345793D01*
X351548Y345432D01*
X351778Y344915D01*
X351855Y344450D01*
X350245D01*
G01X347950Y347550D02*
X348257Y347447D01*
X348487Y347188D01*
X348640Y346878D01*
X348755Y346465D01*
X348793Y346000D01*
X348755Y345535D01*
X348640Y345122D01*
X348487Y344812D01*
X348257Y344553D01*
X347950Y344450D01*
X347643Y344553D01*
X347413Y344812D01*
X347260Y345122D01*
X347145Y345535D01*
X347107Y346000D01*
X347145Y346465D01*
X347260Y346878D01*
X347413Y347188D01*
X347643Y347447D01*
X347950Y347550D01*
G01X345578Y345742D02*
X345310Y346103D01*
X345080Y346310D01*
X344773Y346413D01*
X344505Y346310D01*
X344313Y346103D01*
X344160Y345793D01*
X344122Y345432D01*
X344160Y345122D01*
X344313Y344812D01*
X344543Y344553D01*
X344812Y344450D01*
X345118Y344553D01*
X345387Y344863D01*
X345540Y345328D01*
X345578Y345845D01*
X345502Y346517D01*
X345387Y346878D01*
X345195Y347240D01*
X344927Y347498D01*
X344658Y347550D01*
X344390Y347447D01*
X344198Y347188D01*
G01X354917Y356950D02*
Y360050D01*
X353958D01*
X353652Y359895D01*
X353460Y359688D01*
X353383Y359275D01*
X353460Y358862D01*
X353690Y358603D01*
X353958Y358448D01*
X354917D01*
G01X353958D02*
X353383Y356950D01*
G01X351050D02*
Y360050D01*
X351510Y359430D01*
G01Y356950D02*
X350590D01*
G01X348602Y357312D02*
X348333Y357053D01*
X348027Y356950D01*
X347720Y357053D01*
X347452Y357363D01*
X347260Y357828D01*
X347183Y358293D01*
Y358862D01*
X347260Y359327D01*
X347452Y359740D01*
X347682Y359947D01*
X347950Y360050D01*
X348257Y359947D01*
X348487Y359740D01*
X348640Y359430D01*
X348717Y359017D01*
X348640Y358655D01*
X348448Y358293D01*
X348218Y358087D01*
X347950Y358035D01*
X347643Y358138D01*
X347413Y358397D01*
X347183Y358862D01*
G01X345502Y357312D02*
X345233Y357053D01*
X344927Y356950D01*
X344620Y357053D01*
X344352Y357363D01*
X344160Y357828D01*
X344083Y358293D01*
Y358862D01*
X344160Y359327D01*
X344352Y359740D01*
X344582Y359947D01*
X344850Y360050D01*
X345157Y359947D01*
X345387Y359740D01*
X345540Y359430D01*
X345617Y359017D01*
X345540Y358655D01*
X345348Y358293D01*
X345118Y358087D01*
X344850Y358035D01*
X344543Y358138D01*
X344313Y358397D01*
X344083Y358862D01*
G01X354917Y362950D02*
Y366050D01*
X353958D01*
X353652Y365895D01*
X353460Y365688D01*
X353383Y365275D01*
X353460Y364862D01*
X353690Y364603D01*
X353958Y364448D01*
X354917D01*
G01X353958D02*
X353383Y362950D01*
G01X351778Y365533D02*
X351548Y365843D01*
X351280Y365998D01*
X350973Y366050D01*
X350590Y365947D01*
X350322Y365688D01*
X350245Y365378D01*
X350283Y365068D01*
X350437Y364810D01*
X351203Y364293D01*
X351548Y363932D01*
X351778Y363415D01*
X351855Y362950D01*
X350245D01*
G01X347950Y366050D02*
X348257Y365947D01*
X348487Y365688D01*
X348640Y365378D01*
X348755Y364965D01*
X348793Y364500D01*
X348755Y364035D01*
X348640Y363622D01*
X348487Y363312D01*
X348257Y363053D01*
X347950Y362950D01*
X347643Y363053D01*
X347413Y363312D01*
X347260Y363622D01*
X347145Y364035D01*
X347107Y364500D01*
X347145Y364965D01*
X347260Y365378D01*
X347413Y365688D01*
X347643Y365947D01*
X347950Y366050D01*
G01X345693Y363570D02*
X345463Y363208D01*
X345157Y363002D01*
X344812Y362950D01*
X344505Y363002D01*
X344198Y363260D01*
X344007Y363570D01*
X343968Y363880D01*
X344045Y364242D01*
X344313Y364500D01*
X344582Y364603D01*
X344927D01*
G01X344582D02*
X344352Y364758D01*
X344160Y365017D01*
X344083Y365327D01*
X344160Y365637D01*
X344352Y365895D01*
X344697Y366050D01*
X345042Y365998D01*
X345387Y365792D01*
G01X360367Y422950D02*
Y426050D01*
X359408D01*
X359102Y425895D01*
X358910Y425688D01*
X358833Y425275D01*
X358910Y424862D01*
X359140Y424603D01*
X359408Y424448D01*
X360367D01*
G01X359408D02*
X358833Y422950D01*
G01X357343Y423415D02*
X357113Y423157D01*
X356845Y423002D01*
X356500Y422950D01*
X356155Y423053D01*
X355887Y423260D01*
X355695Y423622D01*
X355657Y424035D01*
X355733Y424448D01*
X355925Y424707D01*
X356193Y424913D01*
X356462Y424965D01*
X356730Y424913D01*
X357075Y424707D01*
X356960Y426050D01*
X355925D01*
G01X353400Y422950D02*
Y426050D01*
X353860Y425430D01*
G01Y422950D02*
X352940D01*
G01X360417Y426950D02*
Y430050D01*
X359458D01*
X359152Y429895D01*
X358960Y429688D01*
X358883Y429275D01*
X358960Y428862D01*
X359190Y428603D01*
X359458Y428448D01*
X360417D01*
G01X359458D02*
X358883Y426950D01*
G01X357278Y429533D02*
X357048Y429843D01*
X356780Y429998D01*
X356473Y430050D01*
X356090Y429947D01*
X355822Y429688D01*
X355745Y429378D01*
X355783Y429068D01*
X355937Y428810D01*
X356703Y428293D01*
X357048Y427932D01*
X357278Y427415D01*
X357355Y426950D01*
X355745D01*
G01X354178Y428242D02*
X353910Y428603D01*
X353680Y428810D01*
X353373Y428913D01*
X353105Y428810D01*
X352913Y428603D01*
X352760Y428293D01*
X352722Y427932D01*
X352760Y427622D01*
X352913Y427312D01*
X353143Y427053D01*
X353412Y426950D01*
X353718Y427053D01*
X353987Y427363D01*
X354140Y427828D01*
X354178Y428345D01*
X354102Y429017D01*
X353987Y429378D01*
X353795Y429740D01*
X353527Y429998D01*
X353258Y430050D01*
X352990Y429947D01*
X352798Y429688D01*
G01X351193Y427570D02*
X350963Y427208D01*
X350657Y427002D01*
X350312Y426950D01*
X350005Y427002D01*
X349698Y427260D01*
X349507Y427570D01*
X349468Y427880D01*
X349545Y428242D01*
X349813Y428500D01*
X350082Y428603D01*
X350427D01*
G01X350082D02*
X349852Y428758D01*
X349660Y429017D01*
X349583Y429327D01*
X349660Y429637D01*
X349852Y429895D01*
X350197Y430050D01*
X350542Y429998D01*
X350887Y429792D01*
G01X380307Y114292D02*
X380537Y114447D01*
X380805Y114550D01*
X381112D01*
X381457Y114395D01*
X381725Y114137D01*
X381917Y113827D01*
X382070Y113310D01*
X382108Y112845D01*
X382032Y112380D01*
X381917Y112070D01*
X381687Y111760D01*
X381418Y111553D01*
X381150Y111450D01*
X380882D01*
X380613Y111553D01*
X380383Y111708D01*
X380192Y111915D01*
G01X378050Y111450D02*
Y114550D01*
X378510Y113930D01*
G01Y111450D02*
X377590D01*
G01X375678Y112742D02*
X375410Y113103D01*
X375180Y113310D01*
X374873Y113413D01*
X374605Y113310D01*
X374413Y113103D01*
X374260Y112793D01*
X374222Y112432D01*
X374260Y112122D01*
X374413Y111812D01*
X374643Y111553D01*
X374912Y111450D01*
X375218Y111553D01*
X375487Y111863D01*
X375640Y112328D01*
X375678Y112845D01*
X375602Y113517D01*
X375487Y113878D01*
X375295Y114240D01*
X375027Y114498D01*
X374758Y114550D01*
X374490Y114447D01*
X374298Y114188D01*
G01X371390Y111450D02*
Y114550D01*
X372808Y112328D01*
X370892D01*
G01X378807Y126292D02*
X379037Y126447D01*
X379305Y126550D01*
X379612D01*
X379957Y126395D01*
X380225Y126137D01*
X380417Y125827D01*
X380570Y125310D01*
X380608Y124845D01*
X380532Y124380D01*
X380417Y124070D01*
X380187Y123760D01*
X379918Y123553D01*
X379650Y123450D01*
X379382D01*
X379113Y123553D01*
X378883Y123708D01*
X378692Y123915D01*
G01X376550Y123450D02*
Y126550D01*
X377010Y125930D01*
G01Y123450D02*
X376090D01*
G01X374178Y126033D02*
X373948Y126343D01*
X373680Y126498D01*
X373373Y126550D01*
X372990Y126447D01*
X372722Y126188D01*
X372645Y125878D01*
X372683Y125568D01*
X372837Y125310D01*
X373603Y124793D01*
X373948Y124432D01*
X374178Y123915D01*
X374255Y123450D01*
X372645D01*
G01X371193Y123915D02*
X370963Y123657D01*
X370695Y123502D01*
X370350Y123450D01*
X370005Y123553D01*
X369737Y123760D01*
X369545Y124122D01*
X369507Y124535D01*
X369583Y124948D01*
X369775Y125207D01*
X370043Y125413D01*
X370312Y125465D01*
X370580Y125413D01*
X370925Y125207D01*
X370810Y126550D01*
X369775D01*
G01X368867Y135550D02*
Y132450D01*
X367333D01*
G01X365843Y133070D02*
X365613Y132708D01*
X365307Y132502D01*
X364962Y132450D01*
X364655Y132502D01*
X364348Y132760D01*
X364157Y133070D01*
X364118Y133380D01*
X364195Y133742D01*
X364463Y134000D01*
X364732Y134103D01*
X365077D01*
G01X364732D02*
X364502Y134258D01*
X364310Y134517D01*
X364233Y134827D01*
X364310Y135137D01*
X364502Y135395D01*
X364847Y135550D01*
X365192Y135498D01*
X365537Y135292D01*
G01X362743Y132915D02*
X362513Y132657D01*
X362245Y132502D01*
X361900Y132450D01*
X361555Y132553D01*
X361287Y132760D01*
X361095Y133122D01*
X361057Y133535D01*
X361133Y133948D01*
X361325Y134207D01*
X361593Y134413D01*
X361862Y134465D01*
X362130Y134413D01*
X362475Y134207D01*
X362360Y135550D01*
X361325D01*
G01X368807Y210792D02*
X369037Y210947D01*
X369305Y211050D01*
X369612D01*
X369957Y210895D01*
X370225Y210637D01*
X370417Y210327D01*
X370570Y209810D01*
X370608Y209345D01*
X370532Y208880D01*
X370417Y208570D01*
X370187Y208260D01*
X369918Y208053D01*
X369650Y207950D01*
X369382D01*
X369113Y208053D01*
X368883Y208208D01*
X368692Y208415D01*
G01X366550Y207950D02*
Y211050D01*
X367010Y210430D01*
G01Y207950D02*
X366090D01*
G01X364293Y208415D02*
X364063Y208157D01*
X363795Y208002D01*
X363450Y207950D01*
X363105Y208053D01*
X362837Y208260D01*
X362645Y208622D01*
X362607Y209035D01*
X362683Y209448D01*
X362875Y209707D01*
X363143Y209913D01*
X363412Y209965D01*
X363680Y209913D01*
X364025Y209707D01*
X363910Y211050D01*
X362875D01*
G01X360350D02*
X360657Y210947D01*
X360887Y210688D01*
X361040Y210378D01*
X361155Y209965D01*
X361193Y209500D01*
X361155Y209035D01*
X361040Y208622D01*
X360887Y208312D01*
X360657Y208053D01*
X360350Y207950D01*
X360043Y208053D01*
X359813Y208312D01*
X359660Y208622D01*
X359545Y209035D01*
X359507Y209500D01*
X359545Y209965D01*
X359660Y210378D01*
X359813Y210688D01*
X360043Y210947D01*
X360350Y211050D01*
G01X373792Y296693D02*
X373947Y296463D01*
X374050Y296195D01*
Y295888D01*
X373895Y295543D01*
X373637Y295275D01*
X373327Y295083D01*
X372810Y294930D01*
X372345Y294892D01*
X371880Y294968D01*
X371570Y295083D01*
X371260Y295313D01*
X371053Y295582D01*
X370950Y295850D01*
Y296118D01*
X371053Y296387D01*
X371208Y296617D01*
X371415Y296808D01*
G01X370950Y298950D02*
X374050D01*
X373430Y298490D01*
G01X370950D02*
Y299410D01*
G01Y302050D02*
X371002Y302318D01*
X371157Y302625D01*
X371415Y302817D01*
X371777Y302893D01*
X372138Y302817D01*
X372448Y302587D01*
X372603Y302242D01*
Y301858D01*
X372707Y301628D01*
X372965Y301437D01*
X373327Y301360D01*
X373688Y301475D01*
X373947Y301743D01*
X374050Y302050D01*
X373947Y302357D01*
X373688Y302625D01*
X373327Y302740D01*
X372965Y302663D01*
X372707Y302472D01*
X372603Y302242D01*
Y301858D01*
X372448Y301513D01*
X372138Y301283D01*
X371777Y301207D01*
X371415Y301283D01*
X371157Y301475D01*
X371002Y301782D01*
X370950Y302050D01*
G01X374050Y305150D02*
X373947Y304843D01*
X373688Y304613D01*
X373378Y304460D01*
X372965Y304345D01*
X372500Y304307D01*
X372035Y304345D01*
X371622Y304460D01*
X371312Y304613D01*
X371053Y304843D01*
X370950Y305150D01*
X371053Y305457D01*
X371312Y305687D01*
X371622Y305840D01*
X372035Y305955D01*
X372500Y305993D01*
X372965Y305955D01*
X373378Y305840D01*
X373688Y305687D01*
X373947Y305457D01*
X374050Y305150D01*
G01X385417Y312950D02*
Y316050D01*
X384458D01*
X384152Y315895D01*
X383960Y315688D01*
X383883Y315275D01*
X383960Y314862D01*
X384190Y314603D01*
X384458Y314448D01*
X385417D01*
G01X384458D02*
X383883Y312950D01*
G01X381550D02*
Y316050D01*
X382010Y315430D01*
G01Y312950D02*
X381090D01*
G01X378527D02*
X378450Y313622D01*
X378335Y314190D01*
X378182Y314707D01*
X377990Y315275D01*
X377683Y316050D01*
X379217D01*
G01X375427Y312950D02*
X375350Y313622D01*
X375235Y314190D01*
X375082Y314707D01*
X374890Y315275D01*
X374583Y316050D01*
X376117D01*
G01X380917Y344450D02*
Y347550D01*
X379958D01*
X379652Y347395D01*
X379460Y347188D01*
X379383Y346775D01*
X379460Y346362D01*
X379690Y346103D01*
X379958Y345948D01*
X380917D01*
G01X379958D02*
X379383Y344450D01*
G01X377050D02*
Y347550D01*
X377510Y346930D01*
G01Y344450D02*
X376590D01*
G01X374602Y344812D02*
X374333Y344553D01*
X374027Y344450D01*
X373720Y344553D01*
X373452Y344863D01*
X373260Y345328D01*
X373183Y345793D01*
Y346362D01*
X373260Y346827D01*
X373452Y347240D01*
X373682Y347447D01*
X373950Y347550D01*
X374257Y347447D01*
X374487Y347240D01*
X374640Y346930D01*
X374717Y346517D01*
X374640Y346155D01*
X374448Y345793D01*
X374218Y345587D01*
X373950Y345535D01*
X373643Y345638D01*
X373413Y345897D01*
X373183Y346362D01*
G01X370850Y344450D02*
Y347550D01*
X371310Y346930D01*
G01Y344450D02*
X370390D01*
G01X380917Y348450D02*
Y351550D01*
X379958D01*
X379652Y351395D01*
X379460Y351188D01*
X379383Y350775D01*
X379460Y350362D01*
X379690Y350103D01*
X379958Y349948D01*
X380917D01*
G01X379958D02*
X379383Y348450D01*
G01X377778Y351033D02*
X377548Y351343D01*
X377280Y351498D01*
X376973Y351550D01*
X376590Y351447D01*
X376322Y351188D01*
X376245Y350878D01*
X376283Y350568D01*
X376437Y350310D01*
X377203Y349793D01*
X377548Y349432D01*
X377778Y348915D01*
X377855Y348450D01*
X376245D01*
G01X373950Y351550D02*
X374257Y351447D01*
X374487Y351188D01*
X374640Y350878D01*
X374755Y350465D01*
X374793Y350000D01*
X374755Y349535D01*
X374640Y349122D01*
X374487Y348812D01*
X374257Y348553D01*
X373950Y348450D01*
X373643Y348553D01*
X373413Y348812D01*
X373260Y349122D01*
X373145Y349535D01*
X373107Y350000D01*
X373145Y350465D01*
X373260Y350878D01*
X373413Y351188D01*
X373643Y351447D01*
X373950Y351550D01*
G01X370850D02*
X371157Y351447D01*
X371387Y351188D01*
X371540Y350878D01*
X371655Y350465D01*
X371693Y350000D01*
X371655Y349535D01*
X371540Y349122D01*
X371387Y348812D01*
X371157Y348553D01*
X370850Y348450D01*
X370543Y348553D01*
X370313Y348812D01*
X370160Y349122D01*
X370045Y349535D01*
X370007Y350000D01*
X370045Y350465D01*
X370160Y350878D01*
X370313Y351188D01*
X370543Y351447D01*
X370850Y351550D01*
G01X380917Y352950D02*
Y356050D01*
X379958D01*
X379652Y355895D01*
X379460Y355688D01*
X379383Y355275D01*
X379460Y354862D01*
X379690Y354603D01*
X379958Y354448D01*
X380917D01*
G01X379958D02*
X379383Y352950D01*
G01X377778Y355533D02*
X377548Y355843D01*
X377280Y355998D01*
X376973Y356050D01*
X376590Y355947D01*
X376322Y355688D01*
X376245Y355378D01*
X376283Y355068D01*
X376437Y354810D01*
X377203Y354293D01*
X377548Y353932D01*
X377778Y353415D01*
X377855Y352950D01*
X376245D01*
G01X373950Y356050D02*
X374257Y355947D01*
X374487Y355688D01*
X374640Y355378D01*
X374755Y354965D01*
X374793Y354500D01*
X374755Y354035D01*
X374640Y353622D01*
X374487Y353312D01*
X374257Y353053D01*
X373950Y352950D01*
X373643Y353053D01*
X373413Y353312D01*
X373260Y353622D01*
X373145Y354035D01*
X373107Y354500D01*
X373145Y354965D01*
X373260Y355378D01*
X373413Y355688D01*
X373643Y355947D01*
X373950Y356050D01*
G01X370390Y352950D02*
Y356050D01*
X371808Y353828D01*
X369892D01*
G01X380917Y361950D02*
Y365050D01*
X379958D01*
X379652Y364895D01*
X379460Y364688D01*
X379383Y364275D01*
X379460Y363862D01*
X379690Y363603D01*
X379958Y363448D01*
X380917D01*
G01X379958D02*
X379383Y361950D01*
G01X377778Y364533D02*
X377548Y364843D01*
X377280Y364998D01*
X376973Y365050D01*
X376590Y364947D01*
X376322Y364688D01*
X376245Y364378D01*
X376283Y364068D01*
X376437Y363810D01*
X377203Y363293D01*
X377548Y362932D01*
X377778Y362415D01*
X377855Y361950D01*
X376245D01*
G01X373950Y365050D02*
X374257Y364947D01*
X374487Y364688D01*
X374640Y364378D01*
X374755Y363965D01*
X374793Y363500D01*
X374755Y363035D01*
X374640Y362622D01*
X374487Y362312D01*
X374257Y362053D01*
X373950Y361950D01*
X373643Y362053D01*
X373413Y362312D01*
X373260Y362622D01*
X373145Y363035D01*
X373107Y363500D01*
X373145Y363965D01*
X373260Y364378D01*
X373413Y364688D01*
X373643Y364947D01*
X373950Y365050D01*
G01X371693Y362415D02*
X371463Y362157D01*
X371195Y362002D01*
X370850Y361950D01*
X370505Y362053D01*
X370237Y362260D01*
X370045Y362622D01*
X370007Y363035D01*
X370083Y363448D01*
X370275Y363707D01*
X370543Y363913D01*
X370812Y363965D01*
X371080Y363913D01*
X371425Y363707D01*
X371310Y365050D01*
X370275D01*
G01X380917Y357450D02*
Y360550D01*
X379958D01*
X379652Y360395D01*
X379460Y360188D01*
X379383Y359775D01*
X379460Y359362D01*
X379690Y359103D01*
X379958Y358948D01*
X380917D01*
G01X379958D02*
X379383Y357450D01*
G01X377778Y360033D02*
X377548Y360343D01*
X377280Y360498D01*
X376973Y360550D01*
X376590Y360447D01*
X376322Y360188D01*
X376245Y359878D01*
X376283Y359568D01*
X376437Y359310D01*
X377203Y358793D01*
X377548Y358432D01*
X377778Y357915D01*
X377855Y357450D01*
X376245D01*
G01X373950Y360550D02*
X374257Y360447D01*
X374487Y360188D01*
X374640Y359878D01*
X374755Y359465D01*
X374793Y359000D01*
X374755Y358535D01*
X374640Y358122D01*
X374487Y357812D01*
X374257Y357553D01*
X373950Y357450D01*
X373643Y357553D01*
X373413Y357812D01*
X373260Y358122D01*
X373145Y358535D01*
X373107Y359000D01*
X373145Y359465D01*
X373260Y359878D01*
X373413Y360188D01*
X373643Y360447D01*
X373950Y360550D01*
G01X370850Y357450D02*
Y360550D01*
X371310Y359930D01*
G01Y357450D02*
X370390D01*
G01X372667Y387150D02*
Y390250D01*
X371708D01*
X371402Y390095D01*
X371210Y389888D01*
X371133Y389475D01*
X371210Y389062D01*
X371440Y388803D01*
X371708Y388648D01*
X372667D01*
G01X371708D02*
X371133Y387150D01*
G01X369643Y387615D02*
X369413Y387357D01*
X369145Y387202D01*
X368800Y387150D01*
X368455Y387253D01*
X368187Y387460D01*
X367995Y387822D01*
X367957Y388235D01*
X368033Y388648D01*
X368225Y388907D01*
X368493Y389113D01*
X368762Y389165D01*
X369030Y389113D01*
X369375Y388907D01*
X369260Y390250D01*
X368225D01*
G01X365240Y387150D02*
Y390250D01*
X366658Y388028D01*
X364742D01*
G01X371057Y395492D02*
X371287Y395647D01*
X371555Y395750D01*
X371862D01*
X372207Y395595D01*
X372475Y395337D01*
X372667Y395027D01*
X372820Y394510D01*
X372858Y394045D01*
X372782Y393580D01*
X372667Y393270D01*
X372437Y392960D01*
X372168Y392753D01*
X371900Y392650D01*
X371632D01*
X371363Y392753D01*
X371133Y392908D01*
X370942Y393115D01*
G01X369643D02*
X369413Y392857D01*
X369145Y392702D01*
X368800Y392650D01*
X368455Y392753D01*
X368187Y392960D01*
X367995Y393322D01*
X367957Y393735D01*
X368033Y394148D01*
X368225Y394407D01*
X368493Y394613D01*
X368762Y394665D01*
X369030Y394613D01*
X369375Y394407D01*
X369260Y395750D01*
X368225D01*
G01X365240Y392650D02*
Y395750D01*
X366658Y393528D01*
X364742D01*
G01X371307Y404292D02*
X371537Y404447D01*
X371805Y404550D01*
X372112D01*
X372457Y404395D01*
X372725Y404137D01*
X372917Y403827D01*
X373070Y403310D01*
X373108Y402845D01*
X373032Y402380D01*
X372917Y402070D01*
X372687Y401760D01*
X372418Y401553D01*
X372150Y401450D01*
X371882D01*
X371613Y401553D01*
X371383Y401708D01*
X371192Y401915D01*
G01X369778Y404033D02*
X369548Y404343D01*
X369280Y404498D01*
X368973Y404550D01*
X368590Y404447D01*
X368322Y404188D01*
X368245Y403878D01*
X368283Y403568D01*
X368437Y403310D01*
X369203Y402793D01*
X369548Y402432D01*
X369778Y401915D01*
X369855Y401450D01*
X368245D01*
G01X365950D02*
X365682Y401502D01*
X365375Y401657D01*
X365183Y401915D01*
X365107Y402277D01*
X365183Y402638D01*
X365413Y402948D01*
X365758Y403103D01*
X366142D01*
X366372Y403207D01*
X366563Y403465D01*
X366640Y403827D01*
X366525Y404188D01*
X366257Y404447D01*
X365950Y404550D01*
X365643Y404447D01*
X365375Y404188D01*
X365260Y403827D01*
X365337Y403465D01*
X365528Y403207D01*
X365758Y403103D01*
X366142D01*
X366487Y402948D01*
X366717Y402638D01*
X366793Y402277D01*
X366717Y401915D01*
X366525Y401657D01*
X366218Y401502D01*
X365950Y401450D01*
G01X363578Y402742D02*
X363310Y403103D01*
X363080Y403310D01*
X362773Y403413D01*
X362505Y403310D01*
X362313Y403103D01*
X362160Y402793D01*
X362122Y402432D01*
X362160Y402122D01*
X362313Y401812D01*
X362543Y401553D01*
X362812Y401450D01*
X363118Y401553D01*
X363387Y401863D01*
X363540Y402328D01*
X363578Y402845D01*
X363502Y403517D01*
X363387Y403878D01*
X363195Y404240D01*
X362927Y404498D01*
X362658Y404550D01*
X362390Y404447D01*
X362198Y404188D01*
G01X372867Y405950D02*
Y409050D01*
X371908D01*
X371602Y408895D01*
X371410Y408688D01*
X371333Y408275D01*
X371410Y407862D01*
X371640Y407603D01*
X371908Y407448D01*
X372867D01*
G01X371908D02*
X371333Y405950D01*
G01X369843Y406415D02*
X369613Y406157D01*
X369345Y406002D01*
X369000Y405950D01*
X368655Y406053D01*
X368387Y406260D01*
X368195Y406622D01*
X368157Y407035D01*
X368233Y407448D01*
X368425Y407707D01*
X368693Y407913D01*
X368962Y407965D01*
X369230Y407913D01*
X369575Y407707D01*
X369460Y409050D01*
X368425D01*
G01X366743Y406570D02*
X366513Y406208D01*
X366207Y406002D01*
X365862Y405950D01*
X365555Y406002D01*
X365248Y406260D01*
X365057Y406570D01*
X365018Y406880D01*
X365095Y407242D01*
X365363Y407500D01*
X365632Y407603D01*
X365977D01*
G01X365632D02*
X365402Y407758D01*
X365210Y408017D01*
X365133Y408327D01*
X365210Y408637D01*
X365402Y408895D01*
X365747Y409050D01*
X366092Y408998D01*
X366437Y408792D01*
G01X372667Y397150D02*
Y400250D01*
X371708D01*
X371402Y400095D01*
X371210Y399888D01*
X371133Y399475D01*
X371210Y399062D01*
X371440Y398803D01*
X371708Y398648D01*
X372667D01*
G01X371708D02*
X371133Y397150D01*
G01X369643Y397770D02*
X369413Y397408D01*
X369107Y397202D01*
X368762Y397150D01*
X368455Y397202D01*
X368148Y397460D01*
X367957Y397770D01*
X367918Y398080D01*
X367995Y398442D01*
X368263Y398700D01*
X368532Y398803D01*
X368877D01*
G01X368532D02*
X368302Y398958D01*
X368110Y399217D01*
X368033Y399527D01*
X368110Y399837D01*
X368302Y400095D01*
X368647Y400250D01*
X368992Y400198D01*
X369337Y399992D01*
G01X366428Y398442D02*
X366160Y398803D01*
X365930Y399010D01*
X365623Y399113D01*
X365355Y399010D01*
X365163Y398803D01*
X365010Y398493D01*
X364972Y398132D01*
X365010Y397822D01*
X365163Y397512D01*
X365393Y397253D01*
X365662Y397150D01*
X365968Y397253D01*
X366237Y397563D01*
X366390Y398028D01*
X366428Y398545D01*
X366352Y399217D01*
X366237Y399578D01*
X366045Y399940D01*
X365777Y400198D01*
X365508Y400250D01*
X365240Y400147D01*
X365048Y399888D01*
G01X386792Y73693D02*
X386947Y73463D01*
X387050Y73195D01*
Y72888D01*
X386895Y72543D01*
X386637Y72275D01*
X386327Y72083D01*
X385810Y71930D01*
X385345Y71892D01*
X384880Y71968D01*
X384570Y72083D01*
X384260Y72313D01*
X384053Y72582D01*
X383950Y72850D01*
Y73118D01*
X384053Y73387D01*
X384208Y73617D01*
X384415Y73808D01*
G01X386533Y75222D02*
X386843Y75452D01*
X386998Y75720D01*
X387050Y76027D01*
X386947Y76410D01*
X386688Y76678D01*
X386378Y76755D01*
X386068Y76717D01*
X385810Y76563D01*
X385293Y75797D01*
X384932Y75452D01*
X384415Y75222D01*
X383950Y75145D01*
Y76755D01*
G01Y79510D02*
X387050D01*
X384828Y78092D01*
Y80008D01*
G01X384415Y81307D02*
X384157Y81537D01*
X384002Y81805D01*
X383950Y82150D01*
X384053Y82495D01*
X384260Y82763D01*
X384622Y82955D01*
X385035Y82993D01*
X385448Y82917D01*
X385707Y82725D01*
X385913Y82457D01*
X385965Y82188D01*
X385913Y81920D01*
X385707Y81575D01*
X387050Y81690D01*
Y82725D01*
G01X387250Y86267D02*
X384750D01*
Y87333D01*
G01Y89000D02*
X387250D01*
X386750Y88680D01*
G01X384750D02*
Y89320D01*
G01X387250Y91200D02*
X387167Y90987D01*
X386958Y90827D01*
X386708Y90720D01*
X386375Y90640D01*
X386000Y90613D01*
X385625Y90640D01*
X385292Y90720D01*
X385042Y90827D01*
X384833Y90987D01*
X384750Y91200D01*
X384833Y91413D01*
X385042Y91573D01*
X385292Y91680D01*
X385625Y91760D01*
X386000Y91787D01*
X386375Y91760D01*
X386708Y91680D01*
X386958Y91573D01*
X387167Y91413D01*
X387250Y91200D01*
G01X384500Y141000D02*
X397500D01*
G01X402000Y168000D02*
X384500D01*
Y141000D01*
G01X388713Y181292D02*
X388873Y181417D01*
X389060Y181500D01*
X389273D01*
X389513Y181375D01*
X389700Y181167D01*
X389833Y180917D01*
X389940Y180500D01*
X389967Y180125D01*
X389913Y179750D01*
X389833Y179500D01*
X389673Y179250D01*
X389487Y179083D01*
X389300Y179000D01*
X389113D01*
X388927Y179083D01*
X388767Y179208D01*
X388633Y179375D01*
G01X387100Y179000D02*
Y181500D01*
X387420Y181000D01*
G01Y179000D02*
X386780D01*
G01X384900Y181500D02*
X385113Y181417D01*
X385273Y181208D01*
X385380Y180958D01*
X385460Y180625D01*
X385487Y180250D01*
X385460Y179875D01*
X385380Y179542D01*
X385273Y179292D01*
X385113Y179083D01*
X384900Y179000D01*
X384687Y179083D01*
X384527Y179292D01*
X384420Y179542D01*
X384340Y179875D01*
X384313Y180250D01*
X384340Y180625D01*
X384420Y180958D01*
X384527Y181208D01*
X384687Y181417D01*
X384900Y181500D01*
G01X382380Y179000D02*
Y181500D01*
X383367Y179708D01*
X382033D01*
G01X397213Y189242D02*
X397373Y189367D01*
X397560Y189450D01*
X397773D01*
X398013Y189325D01*
X398200Y189117D01*
X398333Y188867D01*
X398440Y188450D01*
X398467Y188075D01*
X398413Y187700D01*
X398333Y187450D01*
X398173Y187200D01*
X397987Y187033D01*
X397800Y186950D01*
X397613D01*
X397427Y187033D01*
X397267Y187158D01*
X397133Y187325D01*
G01X395600Y186950D02*
Y189450D01*
X395920Y188950D01*
G01Y186950D02*
X395280D01*
G01X393907Y187992D02*
X393720Y188283D01*
X393560Y188450D01*
X393347Y188533D01*
X393160Y188450D01*
X393027Y188283D01*
X392920Y188033D01*
X392893Y187742D01*
X392920Y187492D01*
X393027Y187242D01*
X393187Y187033D01*
X393373Y186950D01*
X393587Y187033D01*
X393773Y187283D01*
X393880Y187658D01*
X393907Y188075D01*
X393853Y188617D01*
X393773Y188908D01*
X393640Y189200D01*
X393453Y189408D01*
X393267Y189450D01*
X393080Y189367D01*
X392947Y189158D01*
G01X391253Y186950D02*
X391200Y187492D01*
X391120Y187950D01*
X391013Y188367D01*
X390880Y188825D01*
X390667Y189450D01*
X391733D01*
G01X392713Y197042D02*
X392873Y197167D01*
X393060Y197250D01*
X393273D01*
X393513Y197125D01*
X393700Y196917D01*
X393833Y196667D01*
X393940Y196250D01*
X393967Y195875D01*
X393913Y195500D01*
X393833Y195250D01*
X393673Y195000D01*
X393487Y194833D01*
X393300Y194750D01*
X393113D01*
X392927Y194833D01*
X392767Y194958D01*
X392633Y195125D01*
G01X391607Y196833D02*
X391447Y197083D01*
X391260Y197208D01*
X391047Y197250D01*
X390780Y197167D01*
X390593Y196958D01*
X390540Y196708D01*
X390567Y196458D01*
X390673Y196250D01*
X391207Y195833D01*
X391447Y195542D01*
X391607Y195125D01*
X391660Y194750D01*
X390540D01*
G01X388900D02*
Y197250D01*
X389220Y196750D01*
G01Y194750D02*
X388580D01*
G01X386700D02*
Y197250D01*
X387020Y196750D01*
G01Y194750D02*
X386380D01*
G01X388713Y185042D02*
X388873Y185167D01*
X389060Y185250D01*
X389273D01*
X389513Y185125D01*
X389700Y184917D01*
X389833Y184667D01*
X389940Y184250D01*
X389967Y183875D01*
X389913Y183500D01*
X389833Y183250D01*
X389673Y183000D01*
X389487Y182833D01*
X389300Y182750D01*
X389113D01*
X388927Y182833D01*
X388767Y182958D01*
X388633Y183125D01*
G01X387607Y184833D02*
X387447Y185083D01*
X387260Y185208D01*
X387047Y185250D01*
X386780Y185167D01*
X386593Y184958D01*
X386540Y184708D01*
X386567Y184458D01*
X386673Y184250D01*
X387207Y183833D01*
X387447Y183542D01*
X387607Y183125D01*
X387660Y182750D01*
X386540D01*
G01X384900Y185250D02*
X385113Y185167D01*
X385273Y184958D01*
X385380Y184708D01*
X385460Y184375D01*
X385487Y184000D01*
X385460Y183625D01*
X385380Y183292D01*
X385273Y183042D01*
X385113Y182833D01*
X384900Y182750D01*
X384687Y182833D01*
X384527Y183042D01*
X384420Y183292D01*
X384340Y183625D01*
X384313Y184000D01*
X384340Y184375D01*
X384420Y184708D01*
X384527Y184958D01*
X384687Y185167D01*
X384900Y185250D01*
G01X383287Y183250D02*
X383127Y182958D01*
X382913Y182792D01*
X382673Y182750D01*
X382460Y182792D01*
X382247Y183000D01*
X382113Y183250D01*
X382087Y183500D01*
X382140Y183792D01*
X382327Y184000D01*
X382513Y184083D01*
X382753D01*
G01X382513D02*
X382353Y184208D01*
X382220Y184417D01*
X382167Y184667D01*
X382220Y184917D01*
X382353Y185125D01*
X382593Y185250D01*
X382833Y185208D01*
X383073Y185042D01*
G01X389213Y205042D02*
X389373Y205167D01*
X389560Y205250D01*
X389773D01*
X390013Y205125D01*
X390200Y204917D01*
X390333Y204667D01*
X390440Y204250D01*
X390467Y203875D01*
X390413Y203500D01*
X390333Y203250D01*
X390173Y203000D01*
X389987Y202833D01*
X389800Y202750D01*
X389613D01*
X389427Y202833D01*
X389267Y202958D01*
X389133Y203125D01*
G01X387600Y202750D02*
Y205250D01*
X387920Y204750D01*
G01Y202750D02*
X387280D01*
G01X385987Y203125D02*
X385827Y202917D01*
X385640Y202792D01*
X385400Y202750D01*
X385160Y202833D01*
X384973Y203000D01*
X384840Y203292D01*
X384813Y203625D01*
X384867Y203958D01*
X385000Y204167D01*
X385187Y204333D01*
X385373Y204375D01*
X385560Y204333D01*
X385800Y204167D01*
X385720Y205250D01*
X385000D01*
G01X383253Y202750D02*
X383200Y203292D01*
X383120Y203750D01*
X383013Y204167D01*
X382880Y204625D01*
X382667Y205250D01*
X383733D01*
G01X388807Y222292D02*
X389037Y222447D01*
X389305Y222550D01*
X389612D01*
X389957Y222395D01*
X390225Y222137D01*
X390417Y221827D01*
X390570Y221310D01*
X390608Y220845D01*
X390532Y220380D01*
X390417Y220070D01*
X390187Y219760D01*
X389918Y219553D01*
X389650Y219450D01*
X389382D01*
X389113Y219553D01*
X388883Y219708D01*
X388692Y219915D01*
G01X387278Y222033D02*
X387048Y222343D01*
X386780Y222498D01*
X386473Y222550D01*
X386090Y222447D01*
X385822Y222188D01*
X385745Y221878D01*
X385783Y221568D01*
X385937Y221310D01*
X386703Y220793D01*
X387048Y220432D01*
X387278Y219915D01*
X387355Y219450D01*
X385745D01*
G01X383450D02*
Y222550D01*
X383910Y221930D01*
G01Y219450D02*
X382990D01*
G01X381078Y220742D02*
X380810Y221103D01*
X380580Y221310D01*
X380273Y221413D01*
X380005Y221310D01*
X379813Y221103D01*
X379660Y220793D01*
X379622Y220432D01*
X379660Y220122D01*
X379813Y219812D01*
X380043Y219553D01*
X380312Y219450D01*
X380618Y219553D01*
X380887Y219863D01*
X381040Y220328D01*
X381078Y220845D01*
X381002Y221517D01*
X380887Y221878D01*
X380695Y222240D01*
X380427Y222498D01*
X380158Y222550D01*
X379890Y222447D01*
X379698Y222188D01*
G01X390950Y261083D02*
X394050D01*
Y262042D01*
X393895Y262348D01*
X393688Y262540D01*
X393275Y262617D01*
X392862Y262540D01*
X392603Y262310D01*
X392448Y262042D01*
Y261083D01*
G01Y262042D02*
X390950Y262617D01*
G01Y264950D02*
X394050D01*
X393430Y264490D01*
G01X390950D02*
Y265410D01*
G01Y267973D02*
X391622Y268050D01*
X392190Y268165D01*
X392707Y268318D01*
X393275Y268510D01*
X394050Y268817D01*
Y267283D01*
G01X391570Y270307D02*
X391208Y270537D01*
X391002Y270843D01*
X390950Y271188D01*
X391002Y271495D01*
X391260Y271802D01*
X391570Y271993D01*
X391880Y272032D01*
X392242Y271955D01*
X392500Y271687D01*
X392603Y271418D01*
Y271073D01*
G01Y271418D02*
X392758Y271648D01*
X393017Y271840D01*
X393327Y271917D01*
X393637Y271840D01*
X393895Y271648D01*
X394050Y271303D01*
X393998Y270958D01*
X393792Y270613D01*
G01X385450Y261083D02*
X388550D01*
Y262042D01*
X388395Y262348D01*
X388188Y262540D01*
X387775Y262617D01*
X387362Y262540D01*
X387103Y262310D01*
X386948Y262042D01*
Y261083D01*
G01Y262042D02*
X385450Y262617D01*
G01X388033Y264222D02*
X388343Y264452D01*
X388498Y264720D01*
X388550Y265027D01*
X388447Y265410D01*
X388188Y265678D01*
X387878Y265755D01*
X387568Y265717D01*
X387310Y265563D01*
X386793Y264797D01*
X386432Y264452D01*
X385915Y264222D01*
X385450Y264145D01*
Y265755D01*
G01Y268050D02*
X385502Y268318D01*
X385657Y268625D01*
X385915Y268817D01*
X386277Y268893D01*
X386638Y268817D01*
X386948Y268587D01*
X387103Y268242D01*
Y267858D01*
X387207Y267628D01*
X387465Y267437D01*
X387827Y267360D01*
X388188Y267475D01*
X388447Y267743D01*
X388550Y268050D01*
X388447Y268357D01*
X388188Y268625D01*
X387827Y268740D01*
X387465Y268663D01*
X387207Y268472D01*
X387103Y268242D01*
Y267858D01*
X386948Y267513D01*
X386638Y267283D01*
X386277Y267207D01*
X385915Y267283D01*
X385657Y267475D01*
X385502Y267782D01*
X385450Y268050D01*
G01Y271610D02*
X388550D01*
X386328Y270192D01*
Y272108D01*
G01X379950Y261083D02*
X383050D01*
Y262042D01*
X382895Y262348D01*
X382688Y262540D01*
X382275Y262617D01*
X381862Y262540D01*
X381603Y262310D01*
X381448Y262042D01*
Y261083D01*
G01Y262042D02*
X379950Y262617D01*
G01X382533Y264222D02*
X382843Y264452D01*
X382998Y264720D01*
X383050Y265027D01*
X382947Y265410D01*
X382688Y265678D01*
X382378Y265755D01*
X382068Y265717D01*
X381810Y265563D01*
X381293Y264797D01*
X380932Y264452D01*
X380415Y264222D01*
X379950Y264145D01*
Y265755D01*
G01Y268050D02*
X380002Y268318D01*
X380157Y268625D01*
X380415Y268817D01*
X380777Y268893D01*
X381138Y268817D01*
X381448Y268587D01*
X381603Y268242D01*
Y267858D01*
X381707Y267628D01*
X381965Y267437D01*
X382327Y267360D01*
X382688Y267475D01*
X382947Y267743D01*
X383050Y268050D01*
X382947Y268357D01*
X382688Y268625D01*
X382327Y268740D01*
X381965Y268663D01*
X381707Y268472D01*
X381603Y268242D01*
Y267858D01*
X381448Y267513D01*
X381138Y267283D01*
X380777Y267207D01*
X380415Y267283D01*
X380157Y267475D01*
X380002Y267782D01*
X379950Y268050D01*
G01X381242Y270422D02*
X381603Y270690D01*
X381810Y270920D01*
X381913Y271227D01*
X381810Y271495D01*
X381603Y271687D01*
X381293Y271840D01*
X380932Y271878D01*
X380622Y271840D01*
X380312Y271687D01*
X380053Y271457D01*
X379950Y271188D01*
X380053Y270882D01*
X380363Y270613D01*
X380828Y270460D01*
X381345Y270422D01*
X382017Y270498D01*
X382378Y270613D01*
X382740Y270805D01*
X382998Y271073D01*
X383050Y271342D01*
X382947Y271610D01*
X382688Y271802D01*
G01X398917Y298450D02*
Y301550D01*
X397958D01*
X397652Y301395D01*
X397460Y301188D01*
X397383Y300775D01*
X397460Y300362D01*
X397690Y300103D01*
X397958Y299948D01*
X398917D01*
G01X397958D02*
X397383Y298450D01*
G01X395050D02*
Y301550D01*
X395510Y300930D01*
G01Y298450D02*
X394590D01*
G01X392678Y299742D02*
X392410Y300103D01*
X392180Y300310D01*
X391873Y300413D01*
X391605Y300310D01*
X391413Y300103D01*
X391260Y299793D01*
X391222Y299432D01*
X391260Y299122D01*
X391413Y298812D01*
X391643Y298553D01*
X391912Y298450D01*
X392218Y298553D01*
X392487Y298863D01*
X392640Y299328D01*
X392678Y299845D01*
X392602Y300517D01*
X392487Y300878D01*
X392295Y301240D01*
X392027Y301498D01*
X391758Y301550D01*
X391490Y301447D01*
X391298Y301188D01*
G01X389693Y298915D02*
X389463Y298657D01*
X389195Y298502D01*
X388850Y298450D01*
X388505Y298553D01*
X388237Y298760D01*
X388045Y299122D01*
X388007Y299535D01*
X388083Y299948D01*
X388275Y300207D01*
X388543Y300413D01*
X388812Y300465D01*
X389080Y300413D01*
X389425Y300207D01*
X389310Y301550D01*
X388275D01*
G01X401917Y373950D02*
Y377050D01*
X400958D01*
X400652Y376895D01*
X400460Y376688D01*
X400383Y376275D01*
X400460Y375862D01*
X400690Y375603D01*
X400958Y375448D01*
X401917D01*
G01X400958D02*
X400383Y373950D01*
G01X397590D02*
Y377050D01*
X399008Y374828D01*
X397092D01*
G01X395793Y374415D02*
X395563Y374157D01*
X395295Y374002D01*
X394950Y373950D01*
X394605Y374053D01*
X394337Y374260D01*
X394145Y374622D01*
X394107Y375035D01*
X394183Y375448D01*
X394375Y375707D01*
X394643Y375913D01*
X394912Y375965D01*
X395180Y375913D01*
X395525Y375707D01*
X395410Y377050D01*
X394375D01*
G01X391850Y373950D02*
Y377050D01*
X392310Y376430D01*
G01Y373950D02*
X391390D01*
G01X387917Y385950D02*
Y389050D01*
X386958D01*
X386652Y388895D01*
X386460Y388688D01*
X386383Y388275D01*
X386460Y387862D01*
X386690Y387603D01*
X386958Y387448D01*
X387917D01*
G01X386958D02*
X386383Y385950D01*
G01X383590D02*
Y389050D01*
X385008Y386828D01*
X383092D01*
G01X381793Y386415D02*
X381563Y386157D01*
X381295Y386002D01*
X380950Y385950D01*
X380605Y386053D01*
X380337Y386260D01*
X380145Y386622D01*
X380107Y387035D01*
X380183Y387448D01*
X380375Y387707D01*
X380643Y387913D01*
X380912Y387965D01*
X381180Y387913D01*
X381525Y387707D01*
X381410Y389050D01*
X380375D01*
G01X377850D02*
X378157Y388947D01*
X378387Y388688D01*
X378540Y388378D01*
X378655Y387965D01*
X378693Y387500D01*
X378655Y387035D01*
X378540Y386622D01*
X378387Y386312D01*
X378157Y386053D01*
X377850Y385950D01*
X377543Y386053D01*
X377313Y386312D01*
X377160Y386622D01*
X377045Y387035D01*
X377007Y387500D01*
X377045Y387965D01*
X377160Y388378D01*
X377313Y388688D01*
X377543Y388947D01*
X377850Y389050D01*
G01X405307Y129792D02*
X405537Y129947D01*
X405805Y130050D01*
X406112D01*
X406457Y129895D01*
X406725Y129637D01*
X406917Y129327D01*
X407070Y128810D01*
X407108Y128345D01*
X407032Y127880D01*
X406917Y127570D01*
X406687Y127260D01*
X406418Y127053D01*
X406150Y126950D01*
X405882D01*
X405613Y127053D01*
X405383Y127208D01*
X405192Y127415D01*
G01X403050Y126950D02*
Y130050D01*
X403510Y129430D01*
G01Y126950D02*
X402590D01*
G01X399950D02*
Y130050D01*
X400410Y129430D01*
G01Y126950D02*
X399490D01*
G01X397578Y128242D02*
X397310Y128603D01*
X397080Y128810D01*
X396773Y128913D01*
X396505Y128810D01*
X396313Y128603D01*
X396160Y128293D01*
X396122Y127932D01*
X396160Y127622D01*
X396313Y127312D01*
X396543Y127053D01*
X396812Y126950D01*
X397118Y127053D01*
X397387Y127363D01*
X397540Y127828D01*
X397578Y128345D01*
X397502Y129017D01*
X397387Y129378D01*
X397195Y129740D01*
X396927Y129998D01*
X396658Y130050D01*
X396390Y129947D01*
X396198Y129688D01*
G01X398892Y134750D02*
X399850Y137850D01*
X400808Y134750D01*
G01X400463Y135835D02*
X399237D01*
G01X397500Y134000D02*
X408000D01*
G01X397500Y141000D02*
Y134000D01*
G01X398800Y141200D02*
X399900Y142000D01*
G01X401300Y141200D02*
X398800D01*
G01D02*
X399800Y140300D01*
G01X402000Y142700D02*
X400400D01*
G01X397500Y142800D02*
Y141000D01*
G01X397800Y142800D02*
X397500D01*
G01X408000Y134000D02*
Y145500D01*
G01X402000Y134000D02*
Y142700D01*
G01X408000Y145500D02*
X417500D01*
G01X402000Y168000D02*
Y172500D01*
X407000D01*
Y174000D01*
G01X408000Y177500D02*
X410000D01*
G01X416213Y180542D02*
X416373Y180667D01*
X416560Y180750D01*
X416773D01*
X417013Y180625D01*
X417200Y180417D01*
X417333Y180167D01*
X417440Y179750D01*
X417467Y179375D01*
X417413Y179000D01*
X417333Y178750D01*
X417173Y178500D01*
X416987Y178333D01*
X416800Y178250D01*
X416613D01*
X416427Y178333D01*
X416267Y178458D01*
X416133Y178625D01*
G01X415107Y180333D02*
X414947Y180583D01*
X414760Y180708D01*
X414547Y180750D01*
X414280Y180667D01*
X414093Y180458D01*
X414040Y180208D01*
X414067Y179958D01*
X414173Y179750D01*
X414707Y179333D01*
X414947Y179042D01*
X415107Y178625D01*
X415160Y178250D01*
X414040D01*
G01X412400Y180750D02*
X412613Y180667D01*
X412773Y180458D01*
X412880Y180208D01*
X412960Y179875D01*
X412987Y179500D01*
X412960Y179125D01*
X412880Y178792D01*
X412773Y178542D01*
X412613Y178333D01*
X412400Y178250D01*
X412187Y178333D01*
X412027Y178542D01*
X411920Y178792D01*
X411840Y179125D01*
X411813Y179500D01*
X411840Y179875D01*
X411920Y180208D01*
X412027Y180458D01*
X412187Y180667D01*
X412400Y180750D01*
G01X410200D02*
X410413Y180667D01*
X410573Y180458D01*
X410680Y180208D01*
X410760Y179875D01*
X410787Y179500D01*
X410760Y179125D01*
X410680Y178792D01*
X410573Y178542D01*
X410413Y178333D01*
X410200Y178250D01*
X409987Y178333D01*
X409827Y178542D01*
X409720Y178792D01*
X409640Y179125D01*
X409613Y179500D01*
X409640Y179875D01*
X409720Y180208D01*
X409827Y180458D01*
X409987Y180667D01*
X410200Y180750D01*
G01X398042Y174287D02*
X398167Y174127D01*
X398250Y173940D01*
Y173727D01*
X398125Y173487D01*
X397917Y173300D01*
X397667Y173167D01*
X397250Y173060D01*
X396875Y173033D01*
X396500Y173087D01*
X396250Y173167D01*
X396000Y173327D01*
X395833Y173513D01*
X395750Y173700D01*
Y173887D01*
X395833Y174073D01*
X395958Y174233D01*
X396125Y174367D01*
G01X397833Y175393D02*
X398083Y175553D01*
X398208Y175740D01*
X398250Y175953D01*
X398167Y176220D01*
X397958Y176407D01*
X397708Y176460D01*
X397458Y176433D01*
X397250Y176327D01*
X396833Y175793D01*
X396542Y175553D01*
X396125Y175393D01*
X395750Y175340D01*
Y176460D01*
G01X398250Y178100D02*
X398167Y177887D01*
X397958Y177727D01*
X397708Y177620D01*
X397375Y177540D01*
X397000Y177513D01*
X396625Y177540D01*
X396292Y177620D01*
X396042Y177727D01*
X395833Y177887D01*
X395750Y178100D01*
X395833Y178313D01*
X396042Y178473D01*
X396292Y178580D01*
X396625Y178660D01*
X397000Y178687D01*
X397375Y178660D01*
X397708Y178580D01*
X397958Y178473D01*
X398167Y178313D01*
X398250Y178100D01*
G01X396125Y179713D02*
X395917Y179873D01*
X395792Y180060D01*
X395750Y180300D01*
X395833Y180540D01*
X396000Y180727D01*
X396292Y180860D01*
X396625Y180887D01*
X396958Y180833D01*
X397167Y180700D01*
X397333Y180513D01*
X397375Y180327D01*
X397333Y180140D01*
X397167Y179900D01*
X398250Y179980D01*
Y180700D01*
G01X405713Y177042D02*
X405873Y177167D01*
X406060Y177250D01*
X406273D01*
X406513Y177125D01*
X406700Y176917D01*
X406833Y176667D01*
X406940Y176250D01*
X406967Y175875D01*
X406913Y175500D01*
X406833Y175250D01*
X406673Y175000D01*
X406487Y174833D01*
X406300Y174750D01*
X406113D01*
X405927Y174833D01*
X405767Y174958D01*
X405633Y175125D01*
G01X404100Y174750D02*
Y177250D01*
X404420Y176750D01*
G01Y174750D02*
X403780D01*
G01X401900Y177250D02*
X402113Y177167D01*
X402273Y176958D01*
X402380Y176708D01*
X402460Y176375D01*
X402487Y176000D01*
X402460Y175625D01*
X402380Y175292D01*
X402273Y175042D01*
X402113Y174833D01*
X401900Y174750D01*
X401687Y174833D01*
X401527Y175042D01*
X401420Y175292D01*
X401340Y175625D01*
X401313Y176000D01*
X401340Y176375D01*
X401420Y176708D01*
X401527Y176958D01*
X401687Y177167D01*
X401900Y177250D01*
G01X400207Y175792D02*
X400020Y176083D01*
X399860Y176250D01*
X399647Y176333D01*
X399460Y176250D01*
X399327Y176083D01*
X399220Y175833D01*
X399193Y175542D01*
X399220Y175292D01*
X399327Y175042D01*
X399487Y174833D01*
X399673Y174750D01*
X399887Y174833D01*
X400073Y175083D01*
X400180Y175458D01*
X400207Y175875D01*
X400153Y176417D01*
X400073Y176708D01*
X399940Y177000D01*
X399753Y177208D01*
X399567Y177250D01*
X399380Y177167D01*
X399247Y176958D01*
G01X405042Y199787D02*
X405167Y199627D01*
X405250Y199440D01*
Y199227D01*
X405125Y198987D01*
X404917Y198800D01*
X404667Y198667D01*
X404250Y198560D01*
X403875Y198533D01*
X403500Y198587D01*
X403250Y198667D01*
X403000Y198827D01*
X402833Y199013D01*
X402750Y199200D01*
Y199387D01*
X402833Y199573D01*
X402958Y199733D01*
X403125Y199867D01*
G01X402750Y201400D02*
X405250D01*
X404750Y201080D01*
G01X402750D02*
Y201720D01*
G01Y203547D02*
X403292Y203600D01*
X403750Y203680D01*
X404167Y203787D01*
X404625Y203920D01*
X405250Y204133D01*
Y203067D01*
G01Y205800D02*
X405167Y205587D01*
X404958Y205427D01*
X404708Y205320D01*
X404375Y205240D01*
X404000Y205213D01*
X403625Y205240D01*
X403292Y205320D01*
X403042Y205427D01*
X402833Y205587D01*
X402750Y205800D01*
X402833Y206013D01*
X403042Y206173D01*
X403292Y206280D01*
X403625Y206360D01*
X404000Y206387D01*
X404375Y206360D01*
X404708Y206280D01*
X404958Y206173D01*
X405167Y206013D01*
X405250Y205800D01*
G01X412713Y201042D02*
X412873Y201167D01*
X413060Y201250D01*
X413273D01*
X413513Y201125D01*
X413700Y200917D01*
X413833Y200667D01*
X413940Y200250D01*
X413967Y199875D01*
X413913Y199500D01*
X413833Y199250D01*
X413673Y199000D01*
X413487Y198833D01*
X413300Y198750D01*
X413113D01*
X412927Y198833D01*
X412767Y198958D01*
X412633Y199125D01*
G01X411100Y198750D02*
Y201250D01*
X411420Y200750D01*
G01Y198750D02*
X410780D01*
G01X409487Y199125D02*
X409327Y198917D01*
X409140Y198792D01*
X408900Y198750D01*
X408660Y198833D01*
X408473Y199000D01*
X408340Y199292D01*
X408313Y199625D01*
X408367Y199958D01*
X408500Y200167D01*
X408687Y200333D01*
X408873Y200375D01*
X409060Y200333D01*
X409300Y200167D01*
X409220Y201250D01*
X408500D01*
G01X407287Y199250D02*
X407127Y198958D01*
X406913Y198792D01*
X406673Y198750D01*
X406460Y198792D01*
X406247Y199000D01*
X406113Y199250D01*
X406087Y199500D01*
X406140Y199792D01*
X406327Y200000D01*
X406513Y200083D01*
X406753D01*
G01X406513D02*
X406353Y200208D01*
X406220Y200417D01*
X406167Y200667D01*
X406220Y200917D01*
X406353Y201125D01*
X406593Y201250D01*
X406833Y201208D01*
X407073Y201042D01*
G01X398542Y212787D02*
X398667Y212627D01*
X398750Y212440D01*
Y212227D01*
X398625Y211987D01*
X398417Y211800D01*
X398167Y211667D01*
X397750Y211560D01*
X397375Y211533D01*
X397000Y211587D01*
X396750Y211667D01*
X396500Y211827D01*
X396333Y212013D01*
X396250Y212200D01*
Y212387D01*
X396333Y212573D01*
X396458Y212733D01*
X396625Y212867D01*
G01X396250Y214400D02*
X398750D01*
X398250Y214080D01*
G01X396250D02*
Y214720D01*
G01Y216920D02*
X398750D01*
X396958Y215933D01*
Y217267D01*
G01X398750Y218800D02*
X398667Y218587D01*
X398458Y218427D01*
X398208Y218320D01*
X397875Y218240D01*
X397500Y218213D01*
X397125Y218240D01*
X396792Y218320D01*
X396542Y218427D01*
X396333Y218587D01*
X396250Y218800D01*
X396333Y219013D01*
X396542Y219173D01*
X396792Y219280D01*
X397125Y219360D01*
X397500Y219387D01*
X397875Y219360D01*
X398208Y219280D01*
X398458Y219173D01*
X398667Y219013D01*
X398750Y218800D01*
G01X417713Y222742D02*
X417873Y222867D01*
X418060Y222950D01*
X418273D01*
X418513Y222825D01*
X418700Y222617D01*
X418833Y222367D01*
X418940Y221950D01*
X418967Y221575D01*
X418913Y221200D01*
X418833Y220950D01*
X418673Y220700D01*
X418487Y220533D01*
X418300Y220450D01*
X418113D01*
X417927Y220533D01*
X417767Y220658D01*
X417633Y220825D01*
G01X416100Y220450D02*
Y222950D01*
X416420Y222450D01*
G01Y220450D02*
X415780D01*
G01X414487Y220825D02*
X414327Y220617D01*
X414140Y220492D01*
X413900Y220450D01*
X413660Y220533D01*
X413473Y220700D01*
X413340Y220992D01*
X413313Y221325D01*
X413367Y221658D01*
X413500Y221867D01*
X413687Y222033D01*
X413873Y222075D01*
X414060Y222033D01*
X414300Y221867D01*
X414220Y222950D01*
X413500D01*
G01X412153Y220742D02*
X411967Y220533D01*
X411753Y220450D01*
X411540Y220533D01*
X411353Y220783D01*
X411220Y221158D01*
X411167Y221533D01*
Y221992D01*
X411220Y222367D01*
X411353Y222700D01*
X411513Y222867D01*
X411700Y222950D01*
X411913Y222867D01*
X412073Y222700D01*
X412180Y222450D01*
X412233Y222117D01*
X412180Y221825D01*
X412047Y221533D01*
X411887Y221367D01*
X411700Y221325D01*
X411487Y221408D01*
X411327Y221617D01*
X411167Y221992D01*
G01X406307Y242292D02*
X406537Y242447D01*
X406805Y242550D01*
X407112D01*
X407457Y242395D01*
X407725Y242137D01*
X407917Y241827D01*
X408070Y241310D01*
X408108Y240845D01*
X408032Y240380D01*
X407917Y240070D01*
X407687Y239760D01*
X407418Y239553D01*
X407150Y239450D01*
X406882D01*
X406613Y239553D01*
X406383Y239708D01*
X406192Y239915D01*
G01X404050Y239450D02*
Y242550D01*
X404510Y241930D01*
G01Y239450D02*
X403590D01*
G01X401027D02*
X400950Y240122D01*
X400835Y240690D01*
X400682Y241207D01*
X400490Y241775D01*
X400183Y242550D01*
X401717D01*
G01X398578Y242033D02*
X398348Y242343D01*
X398080Y242498D01*
X397773Y242550D01*
X397390Y242447D01*
X397122Y242188D01*
X397045Y241878D01*
X397083Y241568D01*
X397237Y241310D01*
X398003Y240793D01*
X398348Y240432D01*
X398578Y239915D01*
X398655Y239450D01*
X397045D01*
G01X401950Y261583D02*
X405050D01*
Y262542D01*
X404895Y262848D01*
X404688Y263040D01*
X404275Y263117D01*
X403862Y263040D01*
X403603Y262810D01*
X403448Y262542D01*
Y261583D01*
G01Y262542D02*
X401950Y263117D01*
G01X404533Y264722D02*
X404843Y264952D01*
X404998Y265220D01*
X405050Y265527D01*
X404947Y265910D01*
X404688Y266178D01*
X404378Y266255D01*
X404068Y266217D01*
X403810Y266063D01*
X403293Y265297D01*
X402932Y264952D01*
X402415Y264722D01*
X401950Y264645D01*
Y266255D01*
G01X402312Y267898D02*
X402053Y268167D01*
X401950Y268473D01*
X402053Y268780D01*
X402363Y269048D01*
X402828Y269240D01*
X403293Y269317D01*
X403862D01*
X404327Y269240D01*
X404740Y269048D01*
X404947Y268818D01*
X405050Y268550D01*
X404947Y268243D01*
X404740Y268013D01*
X404430Y267860D01*
X404017Y267783D01*
X403655Y267860D01*
X403293Y268052D01*
X403087Y268282D01*
X403035Y268550D01*
X403138Y268857D01*
X403397Y269087D01*
X403862Y269317D01*
G01X402570Y270807D02*
X402208Y271037D01*
X402002Y271343D01*
X401950Y271688D01*
X402002Y271995D01*
X402260Y272302D01*
X402570Y272493D01*
X402880Y272532D01*
X403242Y272455D01*
X403500Y272187D01*
X403603Y271918D01*
Y271573D01*
G01Y271918D02*
X403758Y272148D01*
X404017Y272340D01*
X404327Y272417D01*
X404637Y272340D01*
X404895Y272148D01*
X405050Y271803D01*
X404998Y271458D01*
X404792Y271113D01*
G01X395450Y261083D02*
X398550D01*
Y262042D01*
X398395Y262348D01*
X398188Y262540D01*
X397775Y262617D01*
X397362Y262540D01*
X397103Y262310D01*
X396948Y262042D01*
Y261083D01*
G01Y262042D02*
X395450Y262617D01*
G01Y264950D02*
X398550D01*
X397930Y264490D01*
G01X395450D02*
Y265410D01*
G01Y267973D02*
X396122Y268050D01*
X396690Y268165D01*
X397207Y268318D01*
X397775Y268510D01*
X398550Y268817D01*
Y267283D01*
G01X395450Y271150D02*
X398550D01*
X397930Y270690D01*
G01X395450D02*
Y271610D01*
G01X407450Y261583D02*
X410550D01*
Y262542D01*
X410395Y262848D01*
X410188Y263040D01*
X409775Y263117D01*
X409362Y263040D01*
X409103Y262810D01*
X408948Y262542D01*
Y261583D01*
G01Y262542D02*
X407450Y263117D01*
G01X408070Y264607D02*
X407708Y264837D01*
X407502Y265143D01*
X407450Y265488D01*
X407502Y265795D01*
X407760Y266102D01*
X408070Y266293D01*
X408380Y266332D01*
X408742Y266255D01*
X409000Y265987D01*
X409103Y265718D01*
Y265373D01*
G01Y265718D02*
X409258Y265948D01*
X409517Y266140D01*
X409827Y266217D01*
X410137Y266140D01*
X410395Y265948D01*
X410550Y265603D01*
X410498Y265258D01*
X410292Y264913D01*
G01X410550Y268550D02*
X410447Y268243D01*
X410188Y268013D01*
X409878Y267860D01*
X409465Y267745D01*
X409000Y267707D01*
X408535Y267745D01*
X408122Y267860D01*
X407812Y268013D01*
X407553Y268243D01*
X407450Y268550D01*
X407553Y268857D01*
X407812Y269087D01*
X408122Y269240D01*
X408535Y269355D01*
X409000Y269393D01*
X409465Y269355D01*
X409878Y269240D01*
X410188Y269087D01*
X410447Y268857D01*
X410550Y268550D01*
G01X407812Y270998D02*
X407553Y271267D01*
X407450Y271573D01*
X407553Y271880D01*
X407863Y272148D01*
X408328Y272340D01*
X408793Y272417D01*
X409362D01*
X409827Y272340D01*
X410240Y272148D01*
X410447Y271918D01*
X410550Y271650D01*
X410447Y271343D01*
X410240Y271113D01*
X409930Y270960D01*
X409517Y270883D01*
X409155Y270960D01*
X408793Y271152D01*
X408587Y271382D01*
X408535Y271650D01*
X408638Y271957D01*
X408897Y272187D01*
X409362Y272417D01*
G01X405507Y287292D02*
X405737Y287447D01*
X406005Y287550D01*
X406312D01*
X406657Y287395D01*
X406925Y287137D01*
X407117Y286827D01*
X407270Y286310D01*
X407308Y285845D01*
X407232Y285380D01*
X407117Y285070D01*
X406887Y284760D01*
X406618Y284553D01*
X406350Y284450D01*
X406082D01*
X405813Y284553D01*
X405583Y284708D01*
X405392Y284915D01*
G01X403978Y287033D02*
X403748Y287343D01*
X403480Y287498D01*
X403173Y287550D01*
X402790Y287447D01*
X402522Y287188D01*
X402445Y286878D01*
X402483Y286568D01*
X402637Y286310D01*
X403403Y285793D01*
X403748Y285432D01*
X403978Y284915D01*
X404055Y284450D01*
X402445D01*
G01X399690D02*
Y287550D01*
X401108Y285328D01*
X399192D01*
G01X397893Y285070D02*
X397663Y284708D01*
X397357Y284502D01*
X397012Y284450D01*
X396705Y284502D01*
X396398Y284760D01*
X396207Y285070D01*
X396168Y285380D01*
X396245Y285742D01*
X396513Y286000D01*
X396782Y286103D01*
X397127D01*
G01X396782D02*
X396552Y286258D01*
X396360Y286517D01*
X396283Y286827D01*
X396360Y287137D01*
X396552Y287395D01*
X396897Y287550D01*
X397242Y287498D01*
X397587Y287292D01*
G01X405507Y295392D02*
X405737Y295547D01*
X406005Y295650D01*
X406312D01*
X406657Y295495D01*
X406925Y295237D01*
X407117Y294927D01*
X407270Y294410D01*
X407308Y293945D01*
X407232Y293480D01*
X407117Y293170D01*
X406887Y292860D01*
X406618Y292653D01*
X406350Y292550D01*
X406082D01*
X405813Y292653D01*
X405583Y292808D01*
X405392Y293015D01*
G01X403978Y295133D02*
X403748Y295443D01*
X403480Y295598D01*
X403173Y295650D01*
X402790Y295547D01*
X402522Y295288D01*
X402445Y294978D01*
X402483Y294668D01*
X402637Y294410D01*
X403403Y293893D01*
X403748Y293532D01*
X403978Y293015D01*
X404055Y292550D01*
X402445D01*
G01X399690D02*
Y295650D01*
X401108Y293428D01*
X399192D01*
G01X397050Y292550D02*
Y295650D01*
X397510Y295030D01*
G01Y292550D02*
X396590D01*
G01X404917Y315950D02*
Y319050D01*
X403958D01*
X403652Y318895D01*
X403460Y318688D01*
X403383Y318275D01*
X403460Y317862D01*
X403690Y317603D01*
X403958Y317448D01*
X404917D01*
G01X403958D02*
X403383Y315950D01*
G01X400590D02*
Y319050D01*
X402008Y316828D01*
X400092D01*
G01X398793Y316415D02*
X398563Y316157D01*
X398295Y316002D01*
X397950Y315950D01*
X397605Y316053D01*
X397337Y316260D01*
X397145Y316622D01*
X397107Y317035D01*
X397183Y317448D01*
X397375Y317707D01*
X397643Y317913D01*
X397912Y317965D01*
X398180Y317913D01*
X398525Y317707D01*
X398410Y319050D01*
X397375D01*
G01X394850Y315950D02*
X394582Y316002D01*
X394275Y316157D01*
X394083Y316415D01*
X394007Y316777D01*
X394083Y317138D01*
X394313Y317448D01*
X394658Y317603D01*
X395042D01*
X395272Y317707D01*
X395463Y317965D01*
X395540Y318327D01*
X395425Y318688D01*
X395157Y318947D01*
X394850Y319050D01*
X394543Y318947D01*
X394275Y318688D01*
X394160Y318327D01*
X394237Y317965D01*
X394428Y317707D01*
X394658Y317603D01*
X395042D01*
X395387Y317448D01*
X395617Y317138D01*
X395693Y316777D01*
X395617Y316415D01*
X395425Y316157D01*
X395118Y316002D01*
X394850Y315950D01*
G01X405417Y331950D02*
Y335050D01*
X404458D01*
X404152Y334895D01*
X403960Y334688D01*
X403883Y334275D01*
X403960Y333862D01*
X404190Y333603D01*
X404458Y333448D01*
X405417D01*
G01X404458D02*
X403883Y331950D01*
G01X401090D02*
Y335050D01*
X402508Y332828D01*
X400592D01*
G01X399293Y332415D02*
X399063Y332157D01*
X398795Y332002D01*
X398450Y331950D01*
X398105Y332053D01*
X397837Y332260D01*
X397645Y332622D01*
X397607Y333035D01*
X397683Y333448D01*
X397875Y333707D01*
X398143Y333913D01*
X398412Y333965D01*
X398680Y333913D01*
X399025Y333707D01*
X398910Y335050D01*
X397875D01*
G01X395427Y331950D02*
X395350Y332622D01*
X395235Y333190D01*
X395082Y333707D01*
X394890Y334275D01*
X394583Y335050D01*
X396117D01*
G01X404292Y340693D02*
X404447Y340463D01*
X404550Y340195D01*
Y339888D01*
X404395Y339543D01*
X404137Y339275D01*
X403827Y339083D01*
X403310Y338930D01*
X402845Y338892D01*
X402380Y338968D01*
X402070Y339083D01*
X401760Y339313D01*
X401553Y339582D01*
X401450Y339850D01*
Y340118D01*
X401553Y340387D01*
X401708Y340617D01*
X401915Y340808D01*
G01X401450Y342950D02*
X404550D01*
X403930Y342490D01*
G01X401450D02*
Y343410D01*
G01X404033Y345322D02*
X404343Y345552D01*
X404498Y345820D01*
X404550Y346127D01*
X404447Y346510D01*
X404188Y346778D01*
X403878Y346855D01*
X403568Y346817D01*
X403310Y346663D01*
X402793Y345897D01*
X402432Y345552D01*
X401915Y345322D01*
X401450Y345245D01*
Y346855D01*
G01X402070Y348307D02*
X401708Y348537D01*
X401502Y348843D01*
X401450Y349188D01*
X401502Y349495D01*
X401760Y349802D01*
X402070Y349993D01*
X402380Y350032D01*
X402742Y349955D01*
X403000Y349687D01*
X403103Y349418D01*
Y349073D01*
G01Y349418D02*
X403258Y349648D01*
X403517Y349840D01*
X403827Y349917D01*
X404137Y349840D01*
X404395Y349648D01*
X404550Y349303D01*
X404498Y348958D01*
X404292Y348613D01*
G01X432807Y69292D02*
X433037Y69447D01*
X433305Y69550D01*
X433612D01*
X433957Y69395D01*
X434225Y69137D01*
X434417Y68827D01*
X434570Y68310D01*
X434608Y67845D01*
X434532Y67380D01*
X434417Y67070D01*
X434187Y66760D01*
X433918Y66553D01*
X433650Y66450D01*
X433382D01*
X433113Y66553D01*
X432883Y66708D01*
X432692Y66915D01*
G01X431278Y69033D02*
X431048Y69343D01*
X430780Y69498D01*
X430473Y69550D01*
X430090Y69447D01*
X429822Y69188D01*
X429745Y68878D01*
X429783Y68568D01*
X429937Y68310D01*
X430703Y67793D01*
X431048Y67432D01*
X431278Y66915D01*
X431355Y66450D01*
X429745D01*
G01X426990D02*
Y69550D01*
X428408Y67328D01*
X426492D01*
G01X423890Y66450D02*
Y69550D01*
X425308Y67328D01*
X423392D01*
G01X421792Y90693D02*
X421947Y90463D01*
X422050Y90195D01*
Y89888D01*
X421895Y89543D01*
X421637Y89275D01*
X421327Y89083D01*
X420810Y88930D01*
X420345Y88892D01*
X419880Y88968D01*
X419570Y89083D01*
X419260Y89313D01*
X419053Y89582D01*
X418950Y89850D01*
Y90118D01*
X419053Y90387D01*
X419208Y90617D01*
X419415Y90808D01*
G01X421533Y92222D02*
X421843Y92452D01*
X421998Y92720D01*
X422050Y93027D01*
X421947Y93410D01*
X421688Y93678D01*
X421378Y93755D01*
X421068Y93717D01*
X420810Y93563D01*
X420293Y92797D01*
X419932Y92452D01*
X419415Y92222D01*
X418950Y92145D01*
Y93755D01*
G01Y96510D02*
X422050D01*
X419828Y95092D01*
Y97008D01*
G01X418950Y99150D02*
X419002Y99418D01*
X419157Y99725D01*
X419415Y99917D01*
X419777Y99993D01*
X420138Y99917D01*
X420448Y99687D01*
X420603Y99342D01*
Y98958D01*
X420707Y98728D01*
X420965Y98537D01*
X421327Y98460D01*
X421688Y98575D01*
X421947Y98843D01*
X422050Y99150D01*
X421947Y99457D01*
X421688Y99725D01*
X421327Y99840D01*
X420965Y99763D01*
X420707Y99572D01*
X420603Y99342D01*
Y98958D01*
X420448Y98613D01*
X420138Y98383D01*
X419777Y98307D01*
X419415Y98383D01*
X419157Y98575D01*
X419002Y98882D01*
X418950Y99150D01*
G01X417292Y90693D02*
X417447Y90463D01*
X417550Y90195D01*
Y89888D01*
X417395Y89543D01*
X417137Y89275D01*
X416827Y89083D01*
X416310Y88930D01*
X415845Y88892D01*
X415380Y88968D01*
X415070Y89083D01*
X414760Y89313D01*
X414553Y89582D01*
X414450Y89850D01*
Y90118D01*
X414553Y90387D01*
X414708Y90617D01*
X414915Y90808D01*
G01X417033Y92222D02*
X417343Y92452D01*
X417498Y92720D01*
X417550Y93027D01*
X417447Y93410D01*
X417188Y93678D01*
X416878Y93755D01*
X416568Y93717D01*
X416310Y93563D01*
X415793Y92797D01*
X415432Y92452D01*
X414915Y92222D01*
X414450Y92145D01*
Y93755D01*
G01Y96510D02*
X417550D01*
X415328Y95092D01*
Y97008D01*
G01X415742Y98422D02*
X416103Y98690D01*
X416310Y98920D01*
X416413Y99227D01*
X416310Y99495D01*
X416103Y99687D01*
X415793Y99840D01*
X415432Y99878D01*
X415122Y99840D01*
X414812Y99687D01*
X414553Y99457D01*
X414450Y99188D01*
X414553Y98882D01*
X414863Y98613D01*
X415328Y98460D01*
X415845Y98422D01*
X416517Y98498D01*
X416878Y98613D01*
X417240Y98805D01*
X417498Y99073D01*
X417550Y99342D01*
X417447Y99610D01*
X417188Y99802D01*
G01X417500Y138500D02*
X429000D01*
G01X417500Y145500D02*
Y138500D01*
G01X420000Y177500D02*
X421500D01*
G01X424000D02*
X425500D01*
G01X427000Y177000D02*
X428000D01*
Y184500D01*
G01X425542Y189287D02*
X425667Y189127D01*
X425750Y188940D01*
Y188727D01*
X425625Y188487D01*
X425417Y188300D01*
X425167Y188167D01*
X424750Y188060D01*
X424375Y188033D01*
X424000Y188087D01*
X423750Y188167D01*
X423500Y188327D01*
X423333Y188513D01*
X423250Y188700D01*
Y188887D01*
X423333Y189073D01*
X423458Y189233D01*
X423625Y189367D01*
G01X425333Y190393D02*
X425583Y190553D01*
X425708Y190740D01*
X425750Y190953D01*
X425667Y191220D01*
X425458Y191407D01*
X425208Y191460D01*
X424958Y191433D01*
X424750Y191327D01*
X424333Y190793D01*
X424042Y190553D01*
X423625Y190393D01*
X423250Y190340D01*
Y191460D01*
G01X425333Y192593D02*
X425583Y192753D01*
X425708Y192940D01*
X425750Y193153D01*
X425667Y193420D01*
X425458Y193607D01*
X425208Y193660D01*
X424958Y193633D01*
X424750Y193527D01*
X424333Y192993D01*
X424042Y192753D01*
X423625Y192593D01*
X423250Y192540D01*
Y193660D01*
G01Y195300D02*
X425750D01*
X425250Y194980D01*
G01X423250D02*
Y195620D01*
G01X421542Y193787D02*
X421667Y193627D01*
X421750Y193440D01*
Y193227D01*
X421625Y192987D01*
X421417Y192800D01*
X421167Y192667D01*
X420750Y192560D01*
X420375Y192533D01*
X420000Y192587D01*
X419750Y192667D01*
X419500Y192827D01*
X419333Y193013D01*
X419250Y193200D01*
Y193387D01*
X419333Y193573D01*
X419458Y193733D01*
X419625Y193867D01*
G01X419250Y195400D02*
X421750D01*
X421250Y195080D01*
G01X419250D02*
Y195720D01*
G01Y197600D02*
X421750D01*
X421250Y197280D01*
G01X419250D02*
Y197920D01*
G01X419542Y199347D02*
X419333Y199533D01*
X419250Y199747D01*
X419333Y199960D01*
X419583Y200147D01*
X419958Y200280D01*
X420333Y200333D01*
X420792D01*
X421167Y200280D01*
X421500Y200147D01*
X421667Y199987D01*
X421750Y199800D01*
X421667Y199587D01*
X421500Y199427D01*
X421250Y199320D01*
X420917Y199267D01*
X420625Y199320D01*
X420333Y199453D01*
X420167Y199613D01*
X420125Y199800D01*
X420208Y200013D01*
X420417Y200173D01*
X420792Y200333D01*
G01X431042Y212287D02*
X431167Y212127D01*
X431250Y211940D01*
Y211727D01*
X431125Y211487D01*
X430917Y211300D01*
X430667Y211167D01*
X430250Y211060D01*
X429875Y211033D01*
X429500Y211087D01*
X429250Y211167D01*
X429000Y211327D01*
X428833Y211513D01*
X428750Y211700D01*
Y211887D01*
X428833Y212073D01*
X428958Y212233D01*
X429125Y212367D01*
G01X428750Y213900D02*
X431250D01*
X430750Y213580D01*
G01X428750D02*
Y214220D01*
G01X429792Y215593D02*
X430083Y215780D01*
X430250Y215940D01*
X430333Y216153D01*
X430250Y216340D01*
X430083Y216473D01*
X429833Y216580D01*
X429542Y216607D01*
X429292Y216580D01*
X429042Y216473D01*
X428833Y216313D01*
X428750Y216127D01*
X428833Y215913D01*
X429083Y215727D01*
X429458Y215620D01*
X429875Y215593D01*
X430417Y215647D01*
X430708Y215727D01*
X431000Y215860D01*
X431208Y216047D01*
X431250Y216233D01*
X431167Y216420D01*
X430958Y216553D01*
G01X430833Y217793D02*
X431083Y217953D01*
X431208Y218140D01*
X431250Y218353D01*
X431167Y218620D01*
X430958Y218807D01*
X430708Y218860D01*
X430458Y218833D01*
X430250Y218727D01*
X429833Y218193D01*
X429542Y217953D01*
X429125Y217793D01*
X428750Y217740D01*
Y218860D01*
G01X420713Y209042D02*
X420873Y209167D01*
X421060Y209250D01*
X421273D01*
X421513Y209125D01*
X421700Y208917D01*
X421833Y208667D01*
X421940Y208250D01*
X421967Y207875D01*
X421913Y207500D01*
X421833Y207250D01*
X421673Y207000D01*
X421487Y206833D01*
X421300Y206750D01*
X421113D01*
X420927Y206833D01*
X420767Y206958D01*
X420633Y207125D01*
G01X419100Y206750D02*
Y209250D01*
X419420Y208750D01*
G01Y206750D02*
X418780D01*
G01X416900D02*
Y209250D01*
X417220Y208750D01*
G01Y206750D02*
X416580D01*
G01X415207Y208833D02*
X415047Y209083D01*
X414860Y209208D01*
X414647Y209250D01*
X414380Y209167D01*
X414193Y208958D01*
X414140Y208708D01*
X414167Y208458D01*
X414273Y208250D01*
X414807Y207833D01*
X415047Y207542D01*
X415207Y207125D01*
X415260Y206750D01*
X414140D01*
G01X418950Y261583D02*
X422050D01*
Y262542D01*
X421895Y262848D01*
X421688Y263040D01*
X421275Y263117D01*
X420862Y263040D01*
X420603Y262810D01*
X420448Y262542D01*
Y261583D01*
G01Y262542D02*
X418950Y263117D01*
G01X419570Y264607D02*
X419208Y264837D01*
X419002Y265143D01*
X418950Y265488D01*
X419002Y265795D01*
X419260Y266102D01*
X419570Y266293D01*
X419880Y266332D01*
X420242Y266255D01*
X420500Y265987D01*
X420603Y265718D01*
Y265373D01*
G01Y265718D02*
X420758Y265948D01*
X421017Y266140D01*
X421327Y266217D01*
X421637Y266140D01*
X421895Y265948D01*
X422050Y265603D01*
X421998Y265258D01*
X421792Y264913D01*
G01X421533Y267822D02*
X421843Y268052D01*
X421998Y268320D01*
X422050Y268627D01*
X421947Y269010D01*
X421688Y269278D01*
X421378Y269355D01*
X421068Y269317D01*
X420810Y269163D01*
X420293Y268397D01*
X419932Y268052D01*
X419415Y267822D01*
X418950Y267745D01*
Y269355D01*
G01X420242Y270922D02*
X420603Y271190D01*
X420810Y271420D01*
X420913Y271727D01*
X420810Y271995D01*
X420603Y272187D01*
X420293Y272340D01*
X419932Y272378D01*
X419622Y272340D01*
X419312Y272187D01*
X419053Y271957D01*
X418950Y271688D01*
X419053Y271382D01*
X419363Y271113D01*
X419828Y270960D01*
X420345Y270922D01*
X421017Y270998D01*
X421378Y271113D01*
X421740Y271305D01*
X421998Y271573D01*
X422050Y271842D01*
X421947Y272110D01*
X421688Y272302D01*
G01X412950Y261583D02*
X416050D01*
Y262542D01*
X415895Y262848D01*
X415688Y263040D01*
X415275Y263117D01*
X414862Y263040D01*
X414603Y262810D01*
X414448Y262542D01*
Y261583D01*
G01Y262542D02*
X412950Y263117D01*
G01X413570Y264607D02*
X413208Y264837D01*
X413002Y265143D01*
X412950Y265488D01*
X413002Y265795D01*
X413260Y266102D01*
X413570Y266293D01*
X413880Y266332D01*
X414242Y266255D01*
X414500Y265987D01*
X414603Y265718D01*
Y265373D01*
G01Y265718D02*
X414758Y265948D01*
X415017Y266140D01*
X415327Y266217D01*
X415637Y266140D01*
X415895Y265948D01*
X416050Y265603D01*
X415998Y265258D01*
X415792Y264913D01*
G01X415533Y267822D02*
X415843Y268052D01*
X415998Y268320D01*
X416050Y268627D01*
X415947Y269010D01*
X415688Y269278D01*
X415378Y269355D01*
X415068Y269317D01*
X414810Y269163D01*
X414293Y268397D01*
X413932Y268052D01*
X413415Y267822D01*
X412950Y267745D01*
Y269355D01*
G01Y271650D02*
X413002Y271918D01*
X413157Y272225D01*
X413415Y272417D01*
X413777Y272493D01*
X414138Y272417D01*
X414448Y272187D01*
X414603Y271842D01*
Y271458D01*
X414707Y271228D01*
X414965Y271037D01*
X415327Y270960D01*
X415688Y271075D01*
X415947Y271343D01*
X416050Y271650D01*
X415947Y271957D01*
X415688Y272225D01*
X415327Y272340D01*
X414965Y272263D01*
X414707Y272072D01*
X414603Y271842D01*
Y271458D01*
X414448Y271113D01*
X414138Y270883D01*
X413777Y270807D01*
X413415Y270883D01*
X413157Y271075D01*
X413002Y271382D01*
X412950Y271650D01*
G01X431917Y301450D02*
Y304550D01*
X430958D01*
X430652Y304395D01*
X430460Y304188D01*
X430383Y303775D01*
X430460Y303362D01*
X430690Y303103D01*
X430958Y302948D01*
X431917D01*
G01X430958D02*
X430383Y301450D01*
G01X428778Y304033D02*
X428548Y304343D01*
X428280Y304498D01*
X427973Y304550D01*
X427590Y304447D01*
X427322Y304188D01*
X427245Y303878D01*
X427283Y303568D01*
X427437Y303310D01*
X428203Y302793D01*
X428548Y302432D01*
X428778Y301915D01*
X428855Y301450D01*
X427245D01*
G01X425602Y301812D02*
X425333Y301553D01*
X425027Y301450D01*
X424720Y301553D01*
X424452Y301863D01*
X424260Y302328D01*
X424183Y302793D01*
Y303362D01*
X424260Y303827D01*
X424452Y304240D01*
X424682Y304447D01*
X424950Y304550D01*
X425257Y304447D01*
X425487Y304240D01*
X425640Y303930D01*
X425717Y303517D01*
X425640Y303155D01*
X425448Y302793D01*
X425218Y302587D01*
X424950Y302535D01*
X424643Y302638D01*
X424413Y302897D01*
X424183Y303362D01*
G01X422693Y301915D02*
X422463Y301657D01*
X422195Y301502D01*
X421850Y301450D01*
X421505Y301553D01*
X421237Y301760D01*
X421045Y302122D01*
X421007Y302535D01*
X421083Y302948D01*
X421275Y303207D01*
X421543Y303413D01*
X421812Y303465D01*
X422080Y303413D01*
X422425Y303207D01*
X422310Y304550D01*
X421275D01*
G01X423292Y340693D02*
X423447Y340463D01*
X423550Y340195D01*
Y339888D01*
X423395Y339543D01*
X423137Y339275D01*
X422827Y339083D01*
X422310Y338930D01*
X421845Y338892D01*
X421380Y338968D01*
X421070Y339083D01*
X420760Y339313D01*
X420553Y339582D01*
X420450Y339850D01*
Y340118D01*
X420553Y340387D01*
X420708Y340617D01*
X420915Y340808D01*
G01X420450Y342950D02*
X423550D01*
X422930Y342490D01*
G01X420450D02*
Y343410D01*
G01X423550Y346050D02*
X423447Y345743D01*
X423188Y345513D01*
X422878Y345360D01*
X422465Y345245D01*
X422000Y345207D01*
X421535Y345245D01*
X421122Y345360D01*
X420812Y345513D01*
X420553Y345743D01*
X420450Y346050D01*
X420553Y346357D01*
X420812Y346587D01*
X421122Y346740D01*
X421535Y346855D01*
X422000Y346893D01*
X422465Y346855D01*
X422878Y346740D01*
X423188Y346587D01*
X423447Y346357D01*
X423550Y346050D01*
G01X423033Y348422D02*
X423343Y348652D01*
X423498Y348920D01*
X423550Y349227D01*
X423447Y349610D01*
X423188Y349878D01*
X422878Y349955D01*
X422568Y349917D01*
X422310Y349763D01*
X421793Y348997D01*
X421432Y348652D01*
X420915Y348422D01*
X420450Y348345D01*
Y349955D01*
G01X421292Y383693D02*
X421447Y383463D01*
X421550Y383195D01*
Y382888D01*
X421395Y382543D01*
X421137Y382275D01*
X420827Y382083D01*
X420310Y381930D01*
X419845Y381892D01*
X419380Y381968D01*
X419070Y382083D01*
X418760Y382313D01*
X418553Y382582D01*
X418450Y382850D01*
Y383118D01*
X418553Y383387D01*
X418708Y383617D01*
X418915Y383808D01*
G01X419070Y385107D02*
X418708Y385337D01*
X418502Y385643D01*
X418450Y385988D01*
X418502Y386295D01*
X418760Y386602D01*
X419070Y386793D01*
X419380Y386832D01*
X419742Y386755D01*
X420000Y386487D01*
X420103Y386218D01*
Y385873D01*
G01Y386218D02*
X420258Y386448D01*
X420517Y386640D01*
X420827Y386717D01*
X421137Y386640D01*
X421395Y386448D01*
X421550Y386103D01*
X421498Y385758D01*
X421292Y385413D01*
G01X418450Y389050D02*
X421550D01*
X420930Y388590D01*
G01X418450D02*
Y389510D01*
G01X419742Y391422D02*
X420103Y391690D01*
X420310Y391920D01*
X420413Y392227D01*
X420310Y392495D01*
X420103Y392687D01*
X419793Y392840D01*
X419432Y392878D01*
X419122Y392840D01*
X418812Y392687D01*
X418553Y392457D01*
X418450Y392188D01*
X418553Y391882D01*
X418863Y391613D01*
X419328Y391460D01*
X419845Y391422D01*
X420517Y391498D01*
X420878Y391613D01*
X421240Y391805D01*
X421498Y392073D01*
X421550Y392342D01*
X421447Y392610D01*
X421188Y392802D01*
G01X430417Y417450D02*
Y420550D01*
X429458D01*
X429152Y420395D01*
X428960Y420188D01*
X428883Y419775D01*
X428960Y419362D01*
X429190Y419103D01*
X429458Y418948D01*
X430417D01*
G01X429458D02*
X428883Y417450D01*
G01X427393Y418070D02*
X427163Y417708D01*
X426857Y417502D01*
X426512Y417450D01*
X426205Y417502D01*
X425898Y417760D01*
X425707Y418070D01*
X425668Y418380D01*
X425745Y418742D01*
X426013Y419000D01*
X426282Y419103D01*
X426627D01*
G01X426282D02*
X426052Y419258D01*
X425860Y419517D01*
X425783Y419827D01*
X425860Y420137D01*
X426052Y420395D01*
X426397Y420550D01*
X426742Y420498D01*
X427087Y420292D01*
G01X423450Y417450D02*
Y420550D01*
X423910Y419930D01*
G01Y417450D02*
X422990D01*
G01X420427D02*
X420350Y418122D01*
X420235Y418690D01*
X420082Y419207D01*
X419890Y419775D01*
X419583Y420550D01*
X421117D01*
G01X430417Y421450D02*
Y424550D01*
X429458D01*
X429152Y424395D01*
X428960Y424188D01*
X428883Y423775D01*
X428960Y423362D01*
X429190Y423103D01*
X429458Y422948D01*
X430417D01*
G01X429458D02*
X428883Y421450D01*
G01X427393Y422070D02*
X427163Y421708D01*
X426857Y421502D01*
X426512Y421450D01*
X426205Y421502D01*
X425898Y421760D01*
X425707Y422070D01*
X425668Y422380D01*
X425745Y422742D01*
X426013Y423000D01*
X426282Y423103D01*
X426627D01*
G01X426282D02*
X426052Y423258D01*
X425860Y423517D01*
X425783Y423827D01*
X425860Y424137D01*
X426052Y424395D01*
X426397Y424550D01*
X426742Y424498D01*
X427087Y424292D01*
G01X423450Y421450D02*
Y424550D01*
X423910Y423930D01*
G01Y421450D02*
X422990D01*
G01X420350D02*
X420082Y421502D01*
X419775Y421657D01*
X419583Y421915D01*
X419507Y422277D01*
X419583Y422638D01*
X419813Y422948D01*
X420158Y423103D01*
X420542D01*
X420772Y423207D01*
X420963Y423465D01*
X421040Y423827D01*
X420925Y424188D01*
X420657Y424447D01*
X420350Y424550D01*
X420043Y424447D01*
X419775Y424188D01*
X419660Y423827D01*
X419737Y423465D01*
X419928Y423207D01*
X420158Y423103D01*
X420542D01*
X420887Y422948D01*
X421117Y422638D01*
X421193Y422277D01*
X421117Y421915D01*
X420925Y421657D01*
X420618Y421502D01*
X420350Y421450D01*
G01X439450Y94083D02*
X442550D01*
Y95042D01*
X442395Y95348D01*
X442188Y95540D01*
X441775Y95617D01*
X441362Y95540D01*
X441103Y95310D01*
X440948Y95042D01*
Y94083D01*
G01Y95042D02*
X439450Y95617D01*
G01X440070Y97107D02*
X439708Y97337D01*
X439502Y97643D01*
X439450Y97988D01*
X439502Y98295D01*
X439760Y98602D01*
X440070Y98793D01*
X440380Y98832D01*
X440742Y98755D01*
X441000Y98487D01*
X441103Y98218D01*
Y97873D01*
G01Y98218D02*
X441258Y98448D01*
X441517Y98640D01*
X441827Y98717D01*
X442137Y98640D01*
X442395Y98448D01*
X442550Y98103D01*
X442498Y97758D01*
X442292Y97413D01*
G01X439915Y100207D02*
X439657Y100437D01*
X439502Y100705D01*
X439450Y101050D01*
X439553Y101395D01*
X439760Y101663D01*
X440122Y101855D01*
X440535Y101893D01*
X440948Y101817D01*
X441207Y101625D01*
X441413Y101357D01*
X441465Y101088D01*
X441413Y100820D01*
X441207Y100475D01*
X442550Y100590D01*
Y101625D01*
G01X439450Y104150D02*
X439502Y104418D01*
X439657Y104725D01*
X439915Y104917D01*
X440277Y104993D01*
X440638Y104917D01*
X440948Y104687D01*
X441103Y104342D01*
Y103958D01*
X441207Y103728D01*
X441465Y103537D01*
X441827Y103460D01*
X442188Y103575D01*
X442447Y103843D01*
X442550Y104150D01*
X442447Y104457D01*
X442188Y104725D01*
X441827Y104840D01*
X441465Y104763D01*
X441207Y104572D01*
X441103Y104342D01*
Y103958D01*
X440948Y103613D01*
X440638Y103383D01*
X440277Y103307D01*
X439915Y103383D01*
X439657Y103575D01*
X439502Y103882D01*
X439450Y104150D01*
G01X435450Y94083D02*
X438550D01*
Y95042D01*
X438395Y95348D01*
X438188Y95540D01*
X437775Y95617D01*
X437362Y95540D01*
X437103Y95310D01*
X436948Y95042D01*
Y94083D01*
G01Y95042D02*
X435450Y95617D01*
G01X436070Y97107D02*
X435708Y97337D01*
X435502Y97643D01*
X435450Y97988D01*
X435502Y98295D01*
X435760Y98602D01*
X436070Y98793D01*
X436380Y98832D01*
X436742Y98755D01*
X437000Y98487D01*
X437103Y98218D01*
Y97873D01*
G01Y98218D02*
X437258Y98448D01*
X437517Y98640D01*
X437827Y98717D01*
X438137Y98640D01*
X438395Y98448D01*
X438550Y98103D01*
X438498Y97758D01*
X438292Y97413D01*
G01X435915Y100207D02*
X435657Y100437D01*
X435502Y100705D01*
X435450Y101050D01*
X435553Y101395D01*
X435760Y101663D01*
X436122Y101855D01*
X436535Y101893D01*
X436948Y101817D01*
X437207Y101625D01*
X437413Y101357D01*
X437465Y101088D01*
X437413Y100820D01*
X437207Y100475D01*
X438550Y100590D01*
Y101625D01*
G01X435915Y103307D02*
X435657Y103537D01*
X435502Y103805D01*
X435450Y104150D01*
X435553Y104495D01*
X435760Y104763D01*
X436122Y104955D01*
X436535Y104993D01*
X436948Y104917D01*
X437207Y104725D01*
X437413Y104457D01*
X437465Y104188D01*
X437413Y103920D01*
X437207Y103575D01*
X438550Y103690D01*
Y104725D01*
G01X434550Y79133D02*
X431450D01*
Y80667D01*
G01Y83000D02*
X434550D01*
X433930Y82540D01*
G01X431450D02*
Y83460D01*
G01Y86560D02*
X434550D01*
X432328Y85142D01*
Y87058D01*
G01X441542Y124287D02*
X441667Y124127D01*
X441750Y123940D01*
Y123727D01*
X441625Y123487D01*
X441417Y123300D01*
X441167Y123167D01*
X440750Y123060D01*
X440375Y123033D01*
X440000Y123087D01*
X439750Y123167D01*
X439500Y123327D01*
X439333Y123513D01*
X439250Y123700D01*
Y123887D01*
X439333Y124073D01*
X439458Y124233D01*
X439625Y124367D01*
G01X439250Y125900D02*
X441750D01*
X441250Y125580D01*
G01X439250D02*
Y126220D01*
G01X441750Y128100D02*
X441667Y127887D01*
X441458Y127727D01*
X441208Y127620D01*
X440875Y127540D01*
X440500Y127513D01*
X440125Y127540D01*
X439792Y127620D01*
X439542Y127727D01*
X439333Y127887D01*
X439250Y128100D01*
X439333Y128313D01*
X439542Y128473D01*
X439792Y128580D01*
X440125Y128660D01*
X440500Y128687D01*
X440875Y128660D01*
X441208Y128580D01*
X441458Y128473D01*
X441667Y128313D01*
X441750Y128100D01*
G01X439250Y130300D02*
X439292Y130487D01*
X439417Y130700D01*
X439625Y130833D01*
X439917Y130887D01*
X440208Y130833D01*
X440458Y130673D01*
X440583Y130433D01*
Y130167D01*
X440667Y130007D01*
X440875Y129873D01*
X441167Y129820D01*
X441458Y129900D01*
X441667Y130087D01*
X441750Y130300D01*
X441667Y130513D01*
X441458Y130700D01*
X441167Y130780D01*
X440875Y130727D01*
X440667Y130593D01*
X440583Y130433D01*
Y130167D01*
X440458Y129927D01*
X440208Y129767D01*
X439917Y129713D01*
X439625Y129767D01*
X439417Y129900D01*
X439292Y130113D01*
X439250Y130300D01*
G01X429000Y141500D02*
X441500D01*
G01X429000Y138500D02*
Y141500D01*
G01X441500D02*
Y153500D01*
G01X445042Y131287D02*
X445167Y131127D01*
X445250Y130940D01*
Y130727D01*
X445125Y130487D01*
X444917Y130300D01*
X444667Y130167D01*
X444250Y130060D01*
X443875Y130033D01*
X443500Y130087D01*
X443250Y130167D01*
X443000Y130327D01*
X442833Y130513D01*
X442750Y130700D01*
Y130887D01*
X442833Y131073D01*
X442958Y131233D01*
X443125Y131367D01*
G01X442750Y132900D02*
X445250D01*
X444750Y132580D01*
G01X442750D02*
Y133220D01*
G01X443250Y134513D02*
X442958Y134673D01*
X442792Y134887D01*
X442750Y135127D01*
X442792Y135340D01*
X443000Y135553D01*
X443250Y135687D01*
X443500Y135713D01*
X443792Y135660D01*
X444000Y135473D01*
X444083Y135287D01*
Y135047D01*
G01Y135287D02*
X444208Y135447D01*
X444417Y135580D01*
X444667Y135633D01*
X444917Y135580D01*
X445125Y135447D01*
X445250Y135207D01*
X445208Y134967D01*
X445042Y134727D01*
G01X443125Y136713D02*
X442917Y136873D01*
X442792Y137060D01*
X442750Y137300D01*
X442833Y137540D01*
X443000Y137727D01*
X443292Y137860D01*
X443625Y137887D01*
X443958Y137833D01*
X444167Y137700D01*
X444333Y137513D01*
X444375Y137327D01*
X444333Y137140D01*
X444167Y136900D01*
X445250Y136980D01*
Y137700D01*
G01X441500Y153500D02*
X451000D01*
G01X429000Y187500D02*
X452500D01*
Y192000D01*
X457500D01*
G01X444713Y197042D02*
X444873Y197167D01*
X445060Y197250D01*
X445273D01*
X445513Y197125D01*
X445700Y196917D01*
X445833Y196667D01*
X445940Y196250D01*
X445967Y195875D01*
X445913Y195500D01*
X445833Y195250D01*
X445673Y195000D01*
X445487Y194833D01*
X445300Y194750D01*
X445113D01*
X444927Y194833D01*
X444767Y194958D01*
X444633Y195125D01*
G01X443100Y194750D02*
Y197250D01*
X443420Y196750D01*
G01Y194750D02*
X442780D01*
G01X441487Y195250D02*
X441327Y194958D01*
X441113Y194792D01*
X440873Y194750D01*
X440660Y194792D01*
X440447Y195000D01*
X440313Y195250D01*
X440287Y195500D01*
X440340Y195792D01*
X440527Y196000D01*
X440713Y196083D01*
X440953D01*
G01X440713D02*
X440553Y196208D01*
X440420Y196417D01*
X440367Y196667D01*
X440420Y196917D01*
X440553Y197125D01*
X440793Y197250D01*
X441033Y197208D01*
X441273Y197042D01*
G01X439207Y196833D02*
X439047Y197083D01*
X438860Y197208D01*
X438647Y197250D01*
X438380Y197167D01*
X438193Y196958D01*
X438140Y196708D01*
X438167Y196458D01*
X438273Y196250D01*
X438807Y195833D01*
X439047Y195542D01*
X439207Y195125D01*
X439260Y194750D01*
X438140D01*
G01X436042Y189287D02*
X436167Y189127D01*
X436250Y188940D01*
Y188727D01*
X436125Y188487D01*
X435917Y188300D01*
X435667Y188167D01*
X435250Y188060D01*
X434875Y188033D01*
X434500Y188087D01*
X434250Y188167D01*
X434000Y188327D01*
X433833Y188513D01*
X433750Y188700D01*
Y188887D01*
X433833Y189073D01*
X433958Y189233D01*
X434125Y189367D01*
G01X433750Y190900D02*
X436250D01*
X435750Y190580D01*
G01X433750D02*
Y191220D01*
G01Y193420D02*
X436250D01*
X434458Y192433D01*
Y193767D01*
G01X433750Y195620D02*
X436250D01*
X434458Y194633D01*
Y195967D01*
G01X435042Y201787D02*
X435167Y201627D01*
X435250Y201440D01*
Y201227D01*
X435125Y200987D01*
X434917Y200800D01*
X434667Y200667D01*
X434250Y200560D01*
X433875Y200533D01*
X433500Y200587D01*
X433250Y200667D01*
X433000Y200827D01*
X432833Y201013D01*
X432750Y201200D01*
Y201387D01*
X432833Y201573D01*
X432958Y201733D01*
X433125Y201867D01*
G01X432750Y203400D02*
X435250D01*
X434750Y203080D01*
G01X432750D02*
Y203720D01*
G01Y205920D02*
X435250D01*
X433458Y204933D01*
Y206267D01*
G01X433042Y207347D02*
X432833Y207533D01*
X432750Y207747D01*
X432833Y207960D01*
X433083Y208147D01*
X433458Y208280D01*
X433833Y208333D01*
X434292D01*
X434667Y208280D01*
X435000Y208147D01*
X435167Y207987D01*
X435250Y207800D01*
X435167Y207587D01*
X435000Y207427D01*
X434750Y207320D01*
X434417Y207267D01*
X434125Y207320D01*
X433833Y207453D01*
X433667Y207613D01*
X433625Y207800D01*
X433708Y208013D01*
X433917Y208173D01*
X434292Y208333D01*
G01X452713Y213542D02*
X452873Y213667D01*
X453060Y213750D01*
X453273D01*
X453513Y213625D01*
X453700Y213417D01*
X453833Y213167D01*
X453940Y212750D01*
X453967Y212375D01*
X453913Y212000D01*
X453833Y211750D01*
X453673Y211500D01*
X453487Y211333D01*
X453300Y211250D01*
X453113D01*
X452927Y211333D01*
X452767Y211458D01*
X452633Y211625D01*
G01X451100Y211250D02*
Y213750D01*
X451420Y213250D01*
G01Y211250D02*
X450780D01*
G01X449487Y211750D02*
X449327Y211458D01*
X449113Y211292D01*
X448873Y211250D01*
X448660Y211292D01*
X448447Y211500D01*
X448313Y211750D01*
X448287Y212000D01*
X448340Y212292D01*
X448527Y212500D01*
X448713Y212583D01*
X448953D01*
G01X448713D02*
X448553Y212708D01*
X448420Y212917D01*
X448367Y213167D01*
X448420Y213417D01*
X448553Y213625D01*
X448793Y213750D01*
X449033Y213708D01*
X449273Y213542D01*
G01X446380Y211250D02*
Y213750D01*
X447367Y211958D01*
X446033D01*
G01X441542Y223787D02*
X441667Y223627D01*
X441750Y223440D01*
Y223227D01*
X441625Y222987D01*
X441417Y222800D01*
X441167Y222667D01*
X440750Y222560D01*
X440375Y222533D01*
X440000Y222587D01*
X439750Y222667D01*
X439500Y222827D01*
X439333Y223013D01*
X439250Y223200D01*
Y223387D01*
X439333Y223573D01*
X439458Y223733D01*
X439625Y223867D01*
G01X441333Y224893D02*
X441583Y225053D01*
X441708Y225240D01*
X441750Y225453D01*
X441667Y225720D01*
X441458Y225907D01*
X441208Y225960D01*
X440958Y225933D01*
X440750Y225827D01*
X440333Y225293D01*
X440042Y225053D01*
X439625Y224893D01*
X439250Y224840D01*
Y225960D01*
G01X441333Y227093D02*
X441583Y227253D01*
X441708Y227440D01*
X441750Y227653D01*
X441667Y227920D01*
X441458Y228107D01*
X441208Y228160D01*
X440958Y228133D01*
X440750Y228027D01*
X440333Y227493D01*
X440042Y227253D01*
X439625Y227093D01*
X439250Y227040D01*
Y228160D01*
G01X439750Y229213D02*
X439458Y229373D01*
X439292Y229587D01*
X439250Y229827D01*
X439292Y230040D01*
X439500Y230253D01*
X439750Y230387D01*
X440000Y230413D01*
X440292Y230360D01*
X440500Y230173D01*
X440583Y229987D01*
Y229747D01*
G01Y229987D02*
X440708Y230147D01*
X440917Y230280D01*
X441167Y230333D01*
X441417Y230280D01*
X441625Y230147D01*
X441750Y229907D01*
X441708Y229667D01*
X441542Y229427D01*
G01X433450Y253583D02*
X436550D01*
Y254542D01*
X436395Y254848D01*
X436188Y255040D01*
X435775Y255117D01*
X435362Y255040D01*
X435103Y254810D01*
X434948Y254542D01*
Y253583D01*
G01Y254542D02*
X433450Y255117D01*
G01X436033Y256722D02*
X436343Y256952D01*
X436498Y257220D01*
X436550Y257527D01*
X436447Y257910D01*
X436188Y258178D01*
X435878Y258255D01*
X435568Y258217D01*
X435310Y258063D01*
X434793Y257297D01*
X434432Y256952D01*
X433915Y256722D01*
X433450Y256645D01*
Y258255D01*
G01X436550Y260550D02*
X436447Y260243D01*
X436188Y260013D01*
X435878Y259860D01*
X435465Y259745D01*
X435000Y259707D01*
X434535Y259745D01*
X434122Y259860D01*
X433812Y260013D01*
X433553Y260243D01*
X433450Y260550D01*
X433553Y260857D01*
X433812Y261087D01*
X434122Y261240D01*
X434535Y261355D01*
X435000Y261393D01*
X435465Y261355D01*
X435878Y261240D01*
X436188Y261087D01*
X436447Y260857D01*
X436550Y260550D01*
G01X433450Y263573D02*
X434122Y263650D01*
X434690Y263765D01*
X435207Y263918D01*
X435775Y264110D01*
X436550Y264417D01*
Y262883D01*
G01X442450Y251583D02*
X445550D01*
Y252542D01*
X445395Y252848D01*
X445188Y253040D01*
X444775Y253117D01*
X444362Y253040D01*
X444103Y252810D01*
X443948Y252542D01*
Y251583D01*
G01Y252542D02*
X442450Y253117D01*
G01X445033Y254722D02*
X445343Y254952D01*
X445498Y255220D01*
X445550Y255527D01*
X445447Y255910D01*
X445188Y256178D01*
X444878Y256255D01*
X444568Y256217D01*
X444310Y256063D01*
X443793Y255297D01*
X443432Y254952D01*
X442915Y254722D01*
X442450Y254645D01*
Y256255D01*
G01X445033Y257822D02*
X445343Y258052D01*
X445498Y258320D01*
X445550Y258627D01*
X445447Y259010D01*
X445188Y259278D01*
X444878Y259355D01*
X444568Y259317D01*
X444310Y259163D01*
X443793Y258397D01*
X443432Y258052D01*
X442915Y257822D01*
X442450Y257745D01*
Y259355D01*
G01X445550Y261650D02*
X445447Y261343D01*
X445188Y261113D01*
X444878Y260960D01*
X444465Y260845D01*
X444000Y260807D01*
X443535Y260845D01*
X443122Y260960D01*
X442812Y261113D01*
X442553Y261343D01*
X442450Y261650D01*
X442553Y261957D01*
X442812Y262187D01*
X443122Y262340D01*
X443535Y262455D01*
X444000Y262493D01*
X444465Y262455D01*
X444878Y262340D01*
X445188Y262187D01*
X445447Y261957D01*
X445550Y261650D01*
G01X437950Y251583D02*
X441050D01*
Y252542D01*
X440895Y252848D01*
X440688Y253040D01*
X440275Y253117D01*
X439862Y253040D01*
X439603Y252810D01*
X439448Y252542D01*
Y251583D01*
G01Y252542D02*
X437950Y253117D01*
G01X440533Y254722D02*
X440843Y254952D01*
X440998Y255220D01*
X441050Y255527D01*
X440947Y255910D01*
X440688Y256178D01*
X440378Y256255D01*
X440068Y256217D01*
X439810Y256063D01*
X439293Y255297D01*
X438932Y254952D01*
X438415Y254722D01*
X437950Y254645D01*
Y256255D01*
G01Y258550D02*
X441050D01*
X440430Y258090D01*
G01X437950D02*
Y259010D01*
G01X438312Y260998D02*
X438053Y261267D01*
X437950Y261573D01*
X438053Y261880D01*
X438363Y262148D01*
X438828Y262340D01*
X439293Y262417D01*
X439862D01*
X440327Y262340D01*
X440740Y262148D01*
X440947Y261918D01*
X441050Y261650D01*
X440947Y261343D01*
X440740Y261113D01*
X440430Y260960D01*
X440017Y260883D01*
X439655Y260960D01*
X439293Y261152D01*
X439087Y261382D01*
X439035Y261650D01*
X439138Y261957D01*
X439397Y262187D01*
X439862Y262417D01*
G01X444307Y392792D02*
X444537Y392947D01*
X444805Y393050D01*
X445112D01*
X445457Y392895D01*
X445725Y392637D01*
X445917Y392327D01*
X446070Y391810D01*
X446108Y391345D01*
X446032Y390880D01*
X445917Y390570D01*
X445687Y390260D01*
X445418Y390053D01*
X445150Y389950D01*
X444882D01*
X444613Y390053D01*
X444383Y390208D01*
X444192Y390415D01*
G01X442893Y390570D02*
X442663Y390208D01*
X442357Y390002D01*
X442012Y389950D01*
X441705Y390002D01*
X441398Y390260D01*
X441207Y390570D01*
X441168Y390880D01*
X441245Y391242D01*
X441513Y391500D01*
X441782Y391603D01*
X442127D01*
G01X441782D02*
X441552Y391758D01*
X441360Y392017D01*
X441283Y392327D01*
X441360Y392637D01*
X441552Y392895D01*
X441897Y393050D01*
X442242Y392998D01*
X442587Y392792D01*
G01X438950Y389950D02*
Y393050D01*
X439410Y392430D01*
G01Y389950D02*
X438490D01*
G01X436693Y390415D02*
X436463Y390157D01*
X436195Y390002D01*
X435850Y389950D01*
X435505Y390053D01*
X435237Y390260D01*
X435045Y390622D01*
X435007Y391035D01*
X435083Y391448D01*
X435275Y391707D01*
X435543Y391913D01*
X435812Y391965D01*
X436080Y391913D01*
X436425Y391707D01*
X436310Y393050D01*
X435275D01*
G01X443917Y377950D02*
Y381050D01*
X442958D01*
X442652Y380895D01*
X442460Y380688D01*
X442383Y380275D01*
X442460Y379862D01*
X442690Y379603D01*
X442958Y379448D01*
X443917D01*
G01X442958D02*
X442383Y377950D01*
G01X440893Y378570D02*
X440663Y378208D01*
X440357Y378002D01*
X440012Y377950D01*
X439705Y378002D01*
X439398Y378260D01*
X439207Y378570D01*
X439168Y378880D01*
X439245Y379242D01*
X439513Y379500D01*
X439782Y379603D01*
X440127D01*
G01X439782D02*
X439552Y379758D01*
X439360Y380017D01*
X439283Y380327D01*
X439360Y380637D01*
X439552Y380895D01*
X439897Y381050D01*
X440242Y380998D01*
X440587Y380792D01*
G01X436950Y377950D02*
Y381050D01*
X437410Y380430D01*
G01Y377950D02*
X436490D01*
G01X434502Y378312D02*
X434233Y378053D01*
X433927Y377950D01*
X433620Y378053D01*
X433352Y378363D01*
X433160Y378828D01*
X433083Y379293D01*
Y379862D01*
X433160Y380327D01*
X433352Y380740D01*
X433582Y380947D01*
X433850Y381050D01*
X434157Y380947D01*
X434387Y380740D01*
X434540Y380430D01*
X434617Y380017D01*
X434540Y379655D01*
X434348Y379293D01*
X434118Y379087D01*
X433850Y379035D01*
X433543Y379138D01*
X433313Y379397D01*
X433083Y379862D01*
G01X444417Y421950D02*
Y425050D01*
X443458D01*
X443152Y424895D01*
X442960Y424688D01*
X442883Y424275D01*
X442960Y423862D01*
X443190Y423603D01*
X443458Y423448D01*
X444417D01*
G01X443458D02*
X442883Y421950D01*
G01X441393Y422570D02*
X441163Y422208D01*
X440857Y422002D01*
X440512Y421950D01*
X440205Y422002D01*
X439898Y422260D01*
X439707Y422570D01*
X439668Y422880D01*
X439745Y423242D01*
X440013Y423500D01*
X440282Y423603D01*
X440627D01*
G01X440282D02*
X440052Y423758D01*
X439860Y424017D01*
X439783Y424327D01*
X439860Y424637D01*
X440052Y424895D01*
X440397Y425050D01*
X440742Y424998D01*
X441087Y424792D01*
G01X438178Y424533D02*
X437948Y424843D01*
X437680Y424998D01*
X437373Y425050D01*
X436990Y424947D01*
X436722Y424688D01*
X436645Y424378D01*
X436683Y424068D01*
X436837Y423810D01*
X437603Y423293D01*
X437948Y422932D01*
X438178Y422415D01*
X438255Y421950D01*
X436645D01*
G01X435078Y424533D02*
X434848Y424843D01*
X434580Y424998D01*
X434273Y425050D01*
X433890Y424947D01*
X433622Y424688D01*
X433545Y424378D01*
X433583Y424068D01*
X433737Y423810D01*
X434503Y423293D01*
X434848Y422932D01*
X435078Y422415D01*
X435155Y421950D01*
X433545D01*
G01X444417Y417950D02*
Y421050D01*
X443458D01*
X443152Y420895D01*
X442960Y420688D01*
X442883Y420275D01*
X442960Y419862D01*
X443190Y419603D01*
X443458Y419448D01*
X444417D01*
G01X443458D02*
X442883Y417950D01*
G01X441393Y418570D02*
X441163Y418208D01*
X440857Y418002D01*
X440512Y417950D01*
X440205Y418002D01*
X439898Y418260D01*
X439707Y418570D01*
X439668Y418880D01*
X439745Y419242D01*
X440013Y419500D01*
X440282Y419603D01*
X440627D01*
G01X440282D02*
X440052Y419758D01*
X439860Y420017D01*
X439783Y420327D01*
X439860Y420637D01*
X440052Y420895D01*
X440397Y421050D01*
X440742Y420998D01*
X441087Y420792D01*
G01X438178Y420533D02*
X437948Y420843D01*
X437680Y420998D01*
X437373Y421050D01*
X436990Y420947D01*
X436722Y420688D01*
X436645Y420378D01*
X436683Y420068D01*
X436837Y419810D01*
X437603Y419293D01*
X437948Y418932D01*
X438178Y418415D01*
X438255Y417950D01*
X436645D01*
G01X434350D02*
Y421050D01*
X434810Y420430D01*
G01Y417950D02*
X433890D01*
G01X451950Y96583D02*
X455050D01*
Y97542D01*
X454895Y97848D01*
X454688Y98040D01*
X454275Y98117D01*
X453862Y98040D01*
X453603Y97810D01*
X453448Y97542D01*
Y96583D01*
G01Y97542D02*
X451950Y98117D01*
G01Y100910D02*
X455050D01*
X452828Y99492D01*
Y101408D01*
G01X451950Y104010D02*
X455050D01*
X452828Y102592D01*
Y104508D01*
G01X455050Y106650D02*
X454947Y106343D01*
X454688Y106113D01*
X454378Y105960D01*
X453965Y105845D01*
X453500Y105807D01*
X453035Y105845D01*
X452622Y105960D01*
X452312Y106113D01*
X452053Y106343D01*
X451950Y106650D01*
X452053Y106957D01*
X452312Y107187D01*
X452622Y107340D01*
X453035Y107455D01*
X453500Y107493D01*
X453965Y107455D01*
X454378Y107340D01*
X454688Y107187D01*
X454947Y106957D01*
X455050Y106650D01*
G01X456950Y97083D02*
X460050D01*
Y98042D01*
X459895Y98348D01*
X459688Y98540D01*
X459275Y98617D01*
X458862Y98540D01*
X458603Y98310D01*
X458448Y98042D01*
Y97083D01*
G01Y98042D02*
X456950Y98617D01*
G01Y101410D02*
X460050D01*
X457828Y99992D01*
Y101908D01*
G01X456950Y104510D02*
X460050D01*
X457828Y103092D01*
Y105008D01*
G01X456950Y107150D02*
X460050D01*
X459430Y106690D01*
G01X456950D02*
Y107610D01*
G01X467833Y123250D02*
Y125750D01*
X467167D01*
X466953Y125625D01*
X466820Y125458D01*
X466767Y125125D01*
X466820Y124792D01*
X466980Y124583D01*
X467167Y124458D01*
X467833D01*
G01X467167D02*
X466767Y123250D01*
G01X465607Y125333D02*
X465447Y125583D01*
X465260Y125708D01*
X465047Y125750D01*
X464780Y125667D01*
X464593Y125458D01*
X464540Y125208D01*
X464567Y124958D01*
X464673Y124750D01*
X465207Y124333D01*
X465447Y124042D01*
X465607Y123625D01*
X465660Y123250D01*
X464540D01*
G01X462953D02*
X462900Y123792D01*
X462820Y124250D01*
X462713Y124667D01*
X462580Y125125D01*
X462367Y125750D01*
X463433D01*
G01X461287Y123625D02*
X461127Y123417D01*
X460940Y123292D01*
X460700Y123250D01*
X460460Y123333D01*
X460273Y123500D01*
X460140Y123792D01*
X460113Y124125D01*
X460167Y124458D01*
X460300Y124667D01*
X460487Y124833D01*
X460673Y124875D01*
X460860Y124833D01*
X461100Y124667D01*
X461020Y125750D01*
X460300D01*
G01X449542Y133287D02*
X449667Y133127D01*
X449750Y132940D01*
Y132727D01*
X449625Y132487D01*
X449417Y132300D01*
X449167Y132167D01*
X448750Y132060D01*
X448375Y132033D01*
X448000Y132087D01*
X447750Y132167D01*
X447500Y132327D01*
X447333Y132513D01*
X447250Y132700D01*
Y132887D01*
X447333Y133073D01*
X447458Y133233D01*
X447625Y133367D01*
G01X447250Y134900D02*
X449750D01*
X449250Y134580D01*
G01X447250D02*
Y135220D01*
G01X448292Y136593D02*
X448583Y136780D01*
X448750Y136940D01*
X448833Y137153D01*
X448750Y137340D01*
X448583Y137473D01*
X448333Y137580D01*
X448042Y137607D01*
X447792Y137580D01*
X447542Y137473D01*
X447333Y137313D01*
X447250Y137127D01*
X447333Y136913D01*
X447583Y136727D01*
X447958Y136620D01*
X448375Y136593D01*
X448917Y136647D01*
X449208Y136727D01*
X449500Y136860D01*
X449708Y137047D01*
X449750Y137233D01*
X449667Y137420D01*
X449458Y137553D01*
G01X449750Y139300D02*
X449667Y139087D01*
X449458Y138927D01*
X449208Y138820D01*
X448875Y138740D01*
X448500Y138713D01*
X448125Y138740D01*
X447792Y138820D01*
X447542Y138927D01*
X447333Y139087D01*
X447250Y139300D01*
X447333Y139513D01*
X447542Y139673D01*
X447792Y139780D01*
X448125Y139860D01*
X448500Y139887D01*
X448875Y139860D01*
X449208Y139780D01*
X449458Y139673D01*
X449667Y139513D01*
X449750Y139300D01*
G01X461713Y146042D02*
X461873Y146167D01*
X462060Y146250D01*
X462273D01*
X462513Y146125D01*
X462700Y145917D01*
X462833Y145667D01*
X462940Y145250D01*
X462967Y144875D01*
X462913Y144500D01*
X462833Y144250D01*
X462673Y144000D01*
X462487Y143833D01*
X462300Y143750D01*
X462113D01*
X461927Y143833D01*
X461767Y143958D01*
X461633Y144125D01*
G01X460100Y143750D02*
Y146250D01*
X460420Y145750D01*
G01Y143750D02*
X459780D01*
G01X458407Y145833D02*
X458247Y146083D01*
X458060Y146208D01*
X457847Y146250D01*
X457580Y146167D01*
X457393Y145958D01*
X457340Y145708D01*
X457367Y145458D01*
X457473Y145250D01*
X458007Y144833D01*
X458247Y144542D01*
X458407Y144125D01*
X458460Y143750D01*
X457340D01*
G01X455753D02*
X455700Y144292D01*
X455620Y144750D01*
X455513Y145167D01*
X455380Y145625D01*
X455167Y146250D01*
X456233D01*
G01X451000Y160500D02*
X455500D01*
G01X451000Y153500D02*
Y160500D01*
G01X461500Y181000D02*
Y179500D01*
X460000D01*
Y172000D01*
X455500D01*
Y160500D01*
G01X457542Y153887D02*
X457667Y153727D01*
X457750Y153540D01*
Y153327D01*
X457625Y153087D01*
X457417Y152900D01*
X457167Y152767D01*
X456750Y152660D01*
X456375Y152633D01*
X456000Y152687D01*
X455750Y152767D01*
X455500Y152927D01*
X455333Y153113D01*
X455250Y153300D01*
Y153487D01*
X455333Y153673D01*
X455458Y153833D01*
X455625Y153967D01*
G01X455542Y155047D02*
X455333Y155233D01*
X455250Y155447D01*
X455333Y155660D01*
X455583Y155847D01*
X455958Y155980D01*
X456333Y156033D01*
X456792D01*
X457167Y155980D01*
X457500Y155847D01*
X457667Y155687D01*
X457750Y155500D01*
X457667Y155287D01*
X457500Y155127D01*
X457250Y155020D01*
X456917Y154967D01*
X456625Y155020D01*
X456333Y155153D01*
X456167Y155313D01*
X456125Y155500D01*
X456208Y155713D01*
X456417Y155873D01*
X456792Y156033D01*
G01X455750Y157113D02*
X455458Y157273D01*
X455292Y157487D01*
X455250Y157727D01*
X455292Y157940D01*
X455500Y158153D01*
X455750Y158287D01*
X456000Y158313D01*
X456292Y158260D01*
X456500Y158073D01*
X456583Y157887D01*
Y157647D01*
G01Y157887D02*
X456708Y158047D01*
X456917Y158180D01*
X457167Y158233D01*
X457417Y158180D01*
X457625Y158047D01*
X457750Y157807D01*
X457708Y157567D01*
X457542Y157327D01*
G01X454333Y147750D02*
Y150250D01*
X453667D01*
X453453Y150125D01*
X453320Y149958D01*
X453267Y149625D01*
X453320Y149292D01*
X453480Y149083D01*
X453667Y148958D01*
X454333D01*
G01X453667D02*
X453267Y147750D01*
G01X452107Y149833D02*
X451947Y150083D01*
X451760Y150208D01*
X451547Y150250D01*
X451280Y150167D01*
X451093Y149958D01*
X451040Y149708D01*
X451067Y149458D01*
X451173Y149250D01*
X451707Y148833D01*
X451947Y148542D01*
X452107Y148125D01*
X452160Y147750D01*
X451040D01*
G01X449453D02*
X449400Y148292D01*
X449320Y148750D01*
X449213Y149167D01*
X449080Y149625D01*
X448867Y150250D01*
X449933D01*
G01X447200Y147750D02*
X447013Y147792D01*
X446800Y147917D01*
X446667Y148125D01*
X446613Y148417D01*
X446667Y148708D01*
X446827Y148958D01*
X447067Y149083D01*
X447333D01*
X447493Y149167D01*
X447627Y149375D01*
X447680Y149667D01*
X447600Y149958D01*
X447413Y150167D01*
X447200Y150250D01*
X446987Y150167D01*
X446800Y149958D01*
X446720Y149667D01*
X446773Y149375D01*
X446907Y149167D01*
X447067Y149083D01*
X447333D01*
X447573Y148958D01*
X447733Y148708D01*
X447787Y148417D01*
X447733Y148125D01*
X447600Y147917D01*
X447387Y147792D01*
X447200Y147750D01*
G01X462213Y201042D02*
X462373Y201167D01*
X462560Y201250D01*
X462773D01*
X463013Y201125D01*
X463200Y200917D01*
X463333Y200667D01*
X463440Y200250D01*
X463467Y199875D01*
X463413Y199500D01*
X463333Y199250D01*
X463173Y199000D01*
X462987Y198833D01*
X462800Y198750D01*
X462613D01*
X462427Y198833D01*
X462267Y198958D01*
X462133Y199125D01*
G01X461107Y200833D02*
X460947Y201083D01*
X460760Y201208D01*
X460547Y201250D01*
X460280Y201167D01*
X460093Y200958D01*
X460040Y200708D01*
X460067Y200458D01*
X460173Y200250D01*
X460707Y199833D01*
X460947Y199542D01*
X461107Y199125D01*
X461160Y198750D01*
X460040D01*
G01X458400D02*
Y201250D01*
X458720Y200750D01*
G01Y198750D02*
X458080D01*
G01X456787Y199125D02*
X456627Y198917D01*
X456440Y198792D01*
X456200Y198750D01*
X455960Y198833D01*
X455773Y199000D01*
X455640Y199292D01*
X455613Y199625D01*
X455667Y199958D01*
X455800Y200167D01*
X455987Y200333D01*
X456173Y200375D01*
X456360Y200333D01*
X456600Y200167D01*
X456520Y201250D01*
X455800D01*
G01X453042Y198787D02*
X453167Y198627D01*
X453250Y198440D01*
Y198227D01*
X453125Y197987D01*
X452917Y197800D01*
X452667Y197667D01*
X452250Y197560D01*
X451875Y197533D01*
X451500Y197587D01*
X451250Y197667D01*
X451000Y197827D01*
X450833Y198013D01*
X450750Y198200D01*
Y198387D01*
X450833Y198573D01*
X450958Y198733D01*
X451125Y198867D01*
G01X450750Y200400D02*
X453250D01*
X452750Y200080D01*
G01X450750D02*
Y200720D01*
G01X452833Y202093D02*
X453083Y202253D01*
X453208Y202440D01*
X453250Y202653D01*
X453167Y202920D01*
X452958Y203107D01*
X452708Y203160D01*
X452458Y203133D01*
X452250Y203027D01*
X451833Y202493D01*
X451542Y202253D01*
X451125Y202093D01*
X450750Y202040D01*
Y203160D01*
G01X451792Y204293D02*
X452083Y204480D01*
X452250Y204640D01*
X452333Y204853D01*
X452250Y205040D01*
X452083Y205173D01*
X451833Y205280D01*
X451542Y205307D01*
X451292Y205280D01*
X451042Y205173D01*
X450833Y205013D01*
X450750Y204827D01*
X450833Y204613D01*
X451083Y204427D01*
X451458Y204320D01*
X451875Y204293D01*
X452417Y204347D01*
X452708Y204427D01*
X453000Y204560D01*
X453208Y204747D01*
X453250Y204933D01*
X453167Y205120D01*
X452958Y205253D01*
G01X462213Y204542D02*
X462373Y204667D01*
X462560Y204750D01*
X462773D01*
X463013Y204625D01*
X463200Y204417D01*
X463333Y204167D01*
X463440Y203750D01*
X463467Y203375D01*
X463413Y203000D01*
X463333Y202750D01*
X463173Y202500D01*
X462987Y202333D01*
X462800Y202250D01*
X462613D01*
X462427Y202333D01*
X462267Y202458D01*
X462133Y202625D01*
G01X460600Y202250D02*
Y204750D01*
X460920Y204250D01*
G01Y202250D02*
X460280D01*
G01X458987Y202750D02*
X458827Y202458D01*
X458613Y202292D01*
X458373Y202250D01*
X458160Y202292D01*
X457947Y202500D01*
X457813Y202750D01*
X457787Y203000D01*
X457840Y203292D01*
X458027Y203500D01*
X458213Y203583D01*
X458453D01*
G01X458213D02*
X458053Y203708D01*
X457920Y203917D01*
X457867Y204167D01*
X457920Y204417D01*
X458053Y204625D01*
X458293Y204750D01*
X458533Y204708D01*
X458773Y204542D01*
G01X456200Y204750D02*
X456413Y204667D01*
X456573Y204458D01*
X456680Y204208D01*
X456760Y203875D01*
X456787Y203500D01*
X456760Y203125D01*
X456680Y202792D01*
X456573Y202542D01*
X456413Y202333D01*
X456200Y202250D01*
X455987Y202333D01*
X455827Y202542D01*
X455720Y202792D01*
X455640Y203125D01*
X455613Y203500D01*
X455640Y203875D01*
X455720Y204208D01*
X455827Y204458D01*
X455987Y204667D01*
X456200Y204750D01*
G01X464833Y206750D02*
Y209250D01*
X464167D01*
X463953Y209125D01*
X463820Y208958D01*
X463767Y208625D01*
X463820Y208292D01*
X463980Y208083D01*
X464167Y207958D01*
X464833D01*
G01X464167D02*
X463767Y206750D01*
G01X462687Y207125D02*
X462527Y206917D01*
X462340Y206792D01*
X462100Y206750D01*
X461860Y206833D01*
X461673Y207000D01*
X461540Y207292D01*
X461513Y207625D01*
X461567Y207958D01*
X461700Y208167D01*
X461887Y208333D01*
X462073Y208375D01*
X462260Y208333D01*
X462500Y208167D01*
X462420Y209250D01*
X461700D01*
G01X459900D02*
X460113Y209167D01*
X460273Y208958D01*
X460380Y208708D01*
X460460Y208375D01*
X460487Y208000D01*
X460460Y207625D01*
X460380Y207292D01*
X460273Y207042D01*
X460113Y206833D01*
X459900Y206750D01*
X459687Y206833D01*
X459527Y207042D01*
X459420Y207292D01*
X459340Y207625D01*
X459313Y208000D01*
X459340Y208375D01*
X459420Y208708D01*
X459527Y208958D01*
X459687Y209167D01*
X459900Y209250D01*
G01X458287Y207250D02*
X458127Y206958D01*
X457913Y206792D01*
X457673Y206750D01*
X457460Y206792D01*
X457247Y207000D01*
X457113Y207250D01*
X457087Y207500D01*
X457140Y207792D01*
X457327Y208000D01*
X457513Y208083D01*
X457753D01*
G01X457513D02*
X457353Y208208D01*
X457220Y208417D01*
X457167Y208667D01*
X457220Y208917D01*
X457353Y209125D01*
X457593Y209250D01*
X457833Y209208D01*
X458073Y209042D01*
G01X455042Y221787D02*
X455167Y221627D01*
X455250Y221440D01*
Y221227D01*
X455125Y220987D01*
X454917Y220800D01*
X454667Y220667D01*
X454250Y220560D01*
X453875Y220533D01*
X453500Y220587D01*
X453250Y220667D01*
X453000Y220827D01*
X452833Y221013D01*
X452750Y221200D01*
Y221387D01*
X452833Y221573D01*
X452958Y221733D01*
X453125Y221867D01*
G01X452750Y223400D02*
X455250D01*
X454750Y223080D01*
G01X452750D02*
Y223720D01*
G01X453792Y225093D02*
X454083Y225280D01*
X454250Y225440D01*
X454333Y225653D01*
X454250Y225840D01*
X454083Y225973D01*
X453833Y226080D01*
X453542Y226107D01*
X453292Y226080D01*
X453042Y225973D01*
X452833Y225813D01*
X452750Y225627D01*
X452833Y225413D01*
X453083Y225227D01*
X453458Y225120D01*
X453875Y225093D01*
X454417Y225147D01*
X454708Y225227D01*
X455000Y225360D01*
X455208Y225547D01*
X455250Y225733D01*
X455167Y225920D01*
X454958Y226053D01*
G01X453250Y227213D02*
X452958Y227373D01*
X452792Y227587D01*
X452750Y227827D01*
X452792Y228040D01*
X453000Y228253D01*
X453250Y228387D01*
X453500Y228413D01*
X453792Y228360D01*
X454000Y228173D01*
X454083Y227987D01*
Y227747D01*
G01Y227987D02*
X454208Y228147D01*
X454417Y228280D01*
X454667Y228333D01*
X454917Y228280D01*
X455125Y228147D01*
X455250Y227907D01*
X455208Y227667D01*
X455042Y227427D01*
G01X460950Y252083D02*
X464050D01*
Y253042D01*
X463895Y253348D01*
X463688Y253540D01*
X463275Y253617D01*
X462862Y253540D01*
X462603Y253310D01*
X462448Y253042D01*
Y252083D01*
G01Y253042D02*
X460950Y253617D01*
G01X463533Y255222D02*
X463843Y255452D01*
X463998Y255720D01*
X464050Y256027D01*
X463947Y256410D01*
X463688Y256678D01*
X463378Y256755D01*
X463068Y256717D01*
X462810Y256563D01*
X462293Y255797D01*
X461932Y255452D01*
X461415Y255222D01*
X460950Y255145D01*
Y256755D01*
G01X463533Y258322D02*
X463843Y258552D01*
X463998Y258820D01*
X464050Y259127D01*
X463947Y259510D01*
X463688Y259778D01*
X463378Y259855D01*
X463068Y259817D01*
X462810Y259663D01*
X462293Y258897D01*
X461932Y258552D01*
X461415Y258322D01*
X460950Y258245D01*
Y259855D01*
G01Y262610D02*
X464050D01*
X461828Y261192D01*
Y263108D01*
G01X456450Y252083D02*
X459550D01*
Y253042D01*
X459395Y253348D01*
X459188Y253540D01*
X458775Y253617D01*
X458362Y253540D01*
X458103Y253310D01*
X457948Y253042D01*
Y252083D01*
G01Y253042D02*
X456450Y253617D01*
G01X459033Y255222D02*
X459343Y255452D01*
X459498Y255720D01*
X459550Y256027D01*
X459447Y256410D01*
X459188Y256678D01*
X458878Y256755D01*
X458568Y256717D01*
X458310Y256563D01*
X457793Y255797D01*
X457432Y255452D01*
X456915Y255222D01*
X456450Y255145D01*
Y256755D01*
G01X459033Y258322D02*
X459343Y258552D01*
X459498Y258820D01*
X459550Y259127D01*
X459447Y259510D01*
X459188Y259778D01*
X458878Y259855D01*
X458568Y259817D01*
X458310Y259663D01*
X457793Y258897D01*
X457432Y258552D01*
X456915Y258322D01*
X456450Y258245D01*
Y259855D01*
G01X457070Y261307D02*
X456708Y261537D01*
X456502Y261843D01*
X456450Y262188D01*
X456502Y262495D01*
X456760Y262802D01*
X457070Y262993D01*
X457380Y263032D01*
X457742Y262955D01*
X458000Y262687D01*
X458103Y262418D01*
Y262073D01*
G01Y262418D02*
X458258Y262648D01*
X458517Y262840D01*
X458827Y262917D01*
X459137Y262840D01*
X459395Y262648D01*
X459550Y262303D01*
X459498Y261958D01*
X459292Y261613D01*
G01X447450Y252083D02*
X450550D01*
Y253042D01*
X450395Y253348D01*
X450188Y253540D01*
X449775Y253617D01*
X449362Y253540D01*
X449103Y253310D01*
X448948Y253042D01*
Y252083D01*
G01Y253042D02*
X447450Y253617D01*
G01X450033Y255222D02*
X450343Y255452D01*
X450498Y255720D01*
X450550Y256027D01*
X450447Y256410D01*
X450188Y256678D01*
X449878Y256755D01*
X449568Y256717D01*
X449310Y256563D01*
X448793Y255797D01*
X448432Y255452D01*
X447915Y255222D01*
X447450Y255145D01*
Y256755D01*
G01Y259050D02*
X450550D01*
X449930Y258590D01*
G01X447450D02*
Y259510D01*
G01X448742Y261422D02*
X449103Y261690D01*
X449310Y261920D01*
X449413Y262227D01*
X449310Y262495D01*
X449103Y262687D01*
X448793Y262840D01*
X448432Y262878D01*
X448122Y262840D01*
X447812Y262687D01*
X447553Y262457D01*
X447450Y262188D01*
X447553Y261882D01*
X447863Y261613D01*
X448328Y261460D01*
X448845Y261422D01*
X449517Y261498D01*
X449878Y261613D01*
X450240Y261805D01*
X450498Y262073D01*
X450550Y262342D01*
X450447Y262610D01*
X450188Y262802D01*
G01X451950Y252083D02*
X455050D01*
Y253042D01*
X454895Y253348D01*
X454688Y253540D01*
X454275Y253617D01*
X453862Y253540D01*
X453603Y253310D01*
X453448Y253042D01*
Y252083D01*
G01Y253042D02*
X451950Y253617D01*
G01X454533Y255222D02*
X454843Y255452D01*
X454998Y255720D01*
X455050Y256027D01*
X454947Y256410D01*
X454688Y256678D01*
X454378Y256755D01*
X454068Y256717D01*
X453810Y256563D01*
X453293Y255797D01*
X452932Y255452D01*
X452415Y255222D01*
X451950Y255145D01*
Y256755D01*
G01Y259050D02*
X455050D01*
X454430Y258590D01*
G01X451950D02*
Y259510D01*
G01X452415Y261307D02*
X452157Y261537D01*
X452002Y261805D01*
X451950Y262150D01*
X452053Y262495D01*
X452260Y262763D01*
X452622Y262955D01*
X453035Y262993D01*
X453448Y262917D01*
X453707Y262725D01*
X453913Y262457D01*
X453965Y262188D01*
X453913Y261920D01*
X453707Y261575D01*
X455050Y261690D01*
Y262725D01*
G01X457807Y276292D02*
X458037Y276447D01*
X458305Y276550D01*
X458612D01*
X458957Y276395D01*
X459225Y276137D01*
X459417Y275827D01*
X459570Y275310D01*
X459608Y274845D01*
X459532Y274380D01*
X459417Y274070D01*
X459187Y273760D01*
X458918Y273553D01*
X458650Y273450D01*
X458382D01*
X458113Y273553D01*
X457883Y273708D01*
X457692Y273915D01*
G01X456278Y276033D02*
X456048Y276343D01*
X455780Y276498D01*
X455473Y276550D01*
X455090Y276447D01*
X454822Y276188D01*
X454745Y275878D01*
X454783Y275568D01*
X454937Y275310D01*
X455703Y274793D01*
X456048Y274432D01*
X456278Y273915D01*
X456355Y273450D01*
X454745D01*
G01X453178Y276033D02*
X452948Y276343D01*
X452680Y276498D01*
X452373Y276550D01*
X451990Y276447D01*
X451722Y276188D01*
X451645Y275878D01*
X451683Y275568D01*
X451837Y275310D01*
X452603Y274793D01*
X452948Y274432D01*
X453178Y273915D01*
X453255Y273450D01*
X451645D01*
G01X450002Y273812D02*
X449733Y273553D01*
X449427Y273450D01*
X449120Y273553D01*
X448852Y273863D01*
X448660Y274328D01*
X448583Y274793D01*
Y275362D01*
X448660Y275827D01*
X448852Y276240D01*
X449082Y276447D01*
X449350Y276550D01*
X449657Y276447D01*
X449887Y276240D01*
X450040Y275930D01*
X450117Y275517D01*
X450040Y275155D01*
X449848Y274793D01*
X449618Y274587D01*
X449350Y274535D01*
X449043Y274638D01*
X448813Y274897D01*
X448583Y275362D01*
G01X459417Y269450D02*
Y272550D01*
X458458D01*
X458152Y272395D01*
X457960Y272188D01*
X457883Y271775D01*
X457960Y271362D01*
X458190Y271103D01*
X458458Y270948D01*
X459417D01*
G01X458458D02*
X457883Y269450D01*
G01X456278Y272033D02*
X456048Y272343D01*
X455780Y272498D01*
X455473Y272550D01*
X455090Y272447D01*
X454822Y272188D01*
X454745Y271878D01*
X454783Y271568D01*
X454937Y271310D01*
X455703Y270793D01*
X456048Y270432D01*
X456278Y269915D01*
X456355Y269450D01*
X454745D01*
G01X453178Y270742D02*
X452910Y271103D01*
X452680Y271310D01*
X452373Y271413D01*
X452105Y271310D01*
X451913Y271103D01*
X451760Y270793D01*
X451722Y270432D01*
X451760Y270122D01*
X451913Y269812D01*
X452143Y269553D01*
X452412Y269450D01*
X452718Y269553D01*
X452987Y269863D01*
X453140Y270328D01*
X453178Y270845D01*
X453102Y271517D01*
X452987Y271878D01*
X452795Y272240D01*
X452527Y272498D01*
X452258Y272550D01*
X451990Y272447D01*
X451798Y272188D01*
G01X449350Y272550D02*
X449657Y272447D01*
X449887Y272188D01*
X450040Y271878D01*
X450155Y271465D01*
X450193Y271000D01*
X450155Y270535D01*
X450040Y270122D01*
X449887Y269812D01*
X449657Y269553D01*
X449350Y269450D01*
X449043Y269553D01*
X448813Y269812D01*
X448660Y270122D01*
X448545Y270535D01*
X448507Y271000D01*
X448545Y271465D01*
X448660Y271878D01*
X448813Y272188D01*
X449043Y272447D01*
X449350Y272550D01*
G01X457807Y300292D02*
X458037Y300447D01*
X458305Y300550D01*
X458612D01*
X458957Y300395D01*
X459225Y300137D01*
X459417Y299827D01*
X459570Y299310D01*
X459608Y298845D01*
X459532Y298380D01*
X459417Y298070D01*
X459187Y297760D01*
X458918Y297553D01*
X458650Y297450D01*
X458382D01*
X458113Y297553D01*
X457883Y297708D01*
X457692Y297915D01*
G01X456278Y300033D02*
X456048Y300343D01*
X455780Y300498D01*
X455473Y300550D01*
X455090Y300447D01*
X454822Y300188D01*
X454745Y299878D01*
X454783Y299568D01*
X454937Y299310D01*
X455703Y298793D01*
X456048Y298432D01*
X456278Y297915D01*
X456355Y297450D01*
X454745D01*
G01X453102Y297812D02*
X452833Y297553D01*
X452527Y297450D01*
X452220Y297553D01*
X451952Y297863D01*
X451760Y298328D01*
X451683Y298793D01*
Y299362D01*
X451760Y299827D01*
X451952Y300240D01*
X452182Y300447D01*
X452450Y300550D01*
X452757Y300447D01*
X452987Y300240D01*
X453140Y299930D01*
X453217Y299517D01*
X453140Y299155D01*
X452948Y298793D01*
X452718Y298587D01*
X452450Y298535D01*
X452143Y298638D01*
X451913Y298897D01*
X451683Y299362D01*
G01X448890Y297450D02*
Y300550D01*
X450308Y298328D01*
X448392D01*
G01X459417Y301450D02*
Y304550D01*
X458458D01*
X458152Y304395D01*
X457960Y304188D01*
X457883Y303775D01*
X457960Y303362D01*
X458190Y303103D01*
X458458Y302948D01*
X459417D01*
G01X458458D02*
X457883Y301450D01*
G01X456278Y304033D02*
X456048Y304343D01*
X455780Y304498D01*
X455473Y304550D01*
X455090Y304447D01*
X454822Y304188D01*
X454745Y303878D01*
X454783Y303568D01*
X454937Y303310D01*
X455703Y302793D01*
X456048Y302432D01*
X456278Y301915D01*
X456355Y301450D01*
X454745D01*
G01X453178Y304033D02*
X452948Y304343D01*
X452680Y304498D01*
X452373Y304550D01*
X451990Y304447D01*
X451722Y304188D01*
X451645Y303878D01*
X451683Y303568D01*
X451837Y303310D01*
X452603Y302793D01*
X452948Y302432D01*
X453178Y301915D01*
X453255Y301450D01*
X451645D01*
G01X450078Y302742D02*
X449810Y303103D01*
X449580Y303310D01*
X449273Y303413D01*
X449005Y303310D01*
X448813Y303103D01*
X448660Y302793D01*
X448622Y302432D01*
X448660Y302122D01*
X448813Y301812D01*
X449043Y301553D01*
X449312Y301450D01*
X449618Y301553D01*
X449887Y301863D01*
X450040Y302328D01*
X450078Y302845D01*
X450002Y303517D01*
X449887Y303878D01*
X449695Y304240D01*
X449427Y304498D01*
X449158Y304550D01*
X448890Y304447D01*
X448698Y304188D01*
G01X461757Y385792D02*
X461987Y385947D01*
X462255Y386050D01*
X462562D01*
X462907Y385895D01*
X463175Y385637D01*
X463367Y385327D01*
X463520Y384810D01*
X463558Y384345D01*
X463482Y383880D01*
X463367Y383570D01*
X463137Y383260D01*
X462868Y383053D01*
X462600Y382950D01*
X462332D01*
X462063Y383053D01*
X461833Y383208D01*
X461642Y383415D01*
G01X459500Y382950D02*
X459232Y383002D01*
X458925Y383157D01*
X458733Y383415D01*
X458657Y383777D01*
X458733Y384138D01*
X458963Y384448D01*
X459308Y384603D01*
X459692D01*
X459922Y384707D01*
X460113Y384965D01*
X460190Y385327D01*
X460075Y385688D01*
X459807Y385947D01*
X459500Y386050D01*
X459193Y385947D01*
X458925Y385688D01*
X458810Y385327D01*
X458887Y384965D01*
X459078Y384707D01*
X459308Y384603D01*
X459692D01*
X460037Y384448D01*
X460267Y384138D01*
X460343Y383777D01*
X460267Y383415D01*
X460075Y383157D01*
X459768Y383002D01*
X459500Y382950D01*
G01X456400Y386050D02*
X456707Y385947D01*
X456937Y385688D01*
X457090Y385378D01*
X457205Y384965D01*
X457243Y384500D01*
X457205Y384035D01*
X457090Y383622D01*
X456937Y383312D01*
X456707Y383053D01*
X456400Y382950D01*
X456093Y383053D01*
X455863Y383312D01*
X455710Y383622D01*
X455595Y384035D01*
X455557Y384500D01*
X455595Y384965D01*
X455710Y385378D01*
X455863Y385688D01*
X456093Y385947D01*
X456400Y386050D01*
G01X461807Y401292D02*
X462037Y401447D01*
X462305Y401550D01*
X462612D01*
X462957Y401395D01*
X463225Y401137D01*
X463417Y400827D01*
X463570Y400310D01*
X463608Y399845D01*
X463532Y399380D01*
X463417Y399070D01*
X463187Y398760D01*
X462918Y398553D01*
X462650Y398450D01*
X462382D01*
X462113Y398553D01*
X461883Y398708D01*
X461692Y398915D01*
G01X460278Y401033D02*
X460048Y401343D01*
X459780Y401498D01*
X459473Y401550D01*
X459090Y401447D01*
X458822Y401188D01*
X458745Y400878D01*
X458783Y400568D01*
X458937Y400310D01*
X459703Y399793D01*
X460048Y399432D01*
X460278Y398915D01*
X460355Y398450D01*
X458745D01*
G01X456527D02*
X456450Y399122D01*
X456335Y399690D01*
X456182Y400207D01*
X455990Y400775D01*
X455683Y401550D01*
X457217D01*
G01X454193Y399070D02*
X453963Y398708D01*
X453657Y398502D01*
X453312Y398450D01*
X453005Y398502D01*
X452698Y398760D01*
X452507Y399070D01*
X452468Y399380D01*
X452545Y399742D01*
X452813Y400000D01*
X453082Y400103D01*
X453427D01*
G01X453082D02*
X452852Y400258D01*
X452660Y400517D01*
X452583Y400827D01*
X452660Y401137D01*
X452852Y401395D01*
X453197Y401550D01*
X453542Y401498D01*
X453887Y401292D01*
G01X476917Y85450D02*
Y88550D01*
X475958D01*
X475652Y88395D01*
X475460Y88188D01*
X475383Y87775D01*
X475460Y87362D01*
X475690Y87103D01*
X475958Y86948D01*
X476917D01*
G01X475958D02*
X475383Y85450D01*
G01X472590D02*
Y88550D01*
X474008Y86328D01*
X472092D01*
G01X469950Y85450D02*
X469682Y85502D01*
X469375Y85657D01*
X469183Y85915D01*
X469107Y86277D01*
X469183Y86638D01*
X469413Y86948D01*
X469758Y87103D01*
X470142D01*
X470372Y87207D01*
X470563Y87465D01*
X470640Y87827D01*
X470525Y88188D01*
X470257Y88447D01*
X469950Y88550D01*
X469643Y88447D01*
X469375Y88188D01*
X469260Y87827D01*
X469337Y87465D01*
X469528Y87207D01*
X469758Y87103D01*
X470142D01*
X470487Y86948D01*
X470717Y86638D01*
X470793Y86277D01*
X470717Y85915D01*
X470525Y85657D01*
X470218Y85502D01*
X469950Y85450D01*
G01X467693Y86070D02*
X467463Y85708D01*
X467157Y85502D01*
X466812Y85450D01*
X466505Y85502D01*
X466198Y85760D01*
X466007Y86070D01*
X465968Y86380D01*
X466045Y86742D01*
X466313Y87000D01*
X466582Y87103D01*
X466927D01*
G01X466582D02*
X466352Y87258D01*
X466160Y87517D01*
X466083Y87827D01*
X466160Y88137D01*
X466352Y88395D01*
X466697Y88550D01*
X467042Y88498D01*
X467387Y88292D01*
G01X476917Y99950D02*
Y103050D01*
X475958D01*
X475652Y102895D01*
X475460Y102688D01*
X475383Y102275D01*
X475460Y101862D01*
X475690Y101603D01*
X475958Y101448D01*
X476917D01*
G01X475958D02*
X475383Y99950D01*
G01X472590D02*
Y103050D01*
X474008Y100828D01*
X472092D01*
G01X469950Y99950D02*
X469682Y100002D01*
X469375Y100157D01*
X469183Y100415D01*
X469107Y100777D01*
X469183Y101138D01*
X469413Y101448D01*
X469758Y101603D01*
X470142D01*
X470372Y101707D01*
X470563Y101965D01*
X470640Y102327D01*
X470525Y102688D01*
X470257Y102947D01*
X469950Y103050D01*
X469643Y102947D01*
X469375Y102688D01*
X469260Y102327D01*
X469337Y101965D01*
X469528Y101707D01*
X469758Y101603D01*
X470142D01*
X470487Y101448D01*
X470717Y101138D01*
X470793Y100777D01*
X470717Y100415D01*
X470525Y100157D01*
X470218Y100002D01*
X469950Y99950D01*
G01X467578Y102533D02*
X467348Y102843D01*
X467080Y102998D01*
X466773Y103050D01*
X466390Y102947D01*
X466122Y102688D01*
X466045Y102378D01*
X466083Y102068D01*
X466237Y101810D01*
X467003Y101293D01*
X467348Y100932D01*
X467578Y100415D01*
X467655Y99950D01*
X466045D01*
G01X482042Y142787D02*
X482167Y142627D01*
X482250Y142440D01*
Y142227D01*
X482125Y141987D01*
X481917Y141800D01*
X481667Y141667D01*
X481250Y141560D01*
X480875Y141533D01*
X480500Y141587D01*
X480250Y141667D01*
X480000Y141827D01*
X479833Y142013D01*
X479750Y142200D01*
Y142387D01*
X479833Y142573D01*
X479958Y142733D01*
X480125Y142867D01*
G01X479750Y144400D02*
X482250D01*
X481750Y144080D01*
G01X479750D02*
Y144720D01*
G01X481833Y146093D02*
X482083Y146253D01*
X482208Y146440D01*
X482250Y146653D01*
X482167Y146920D01*
X481958Y147107D01*
X481708Y147160D01*
X481458Y147133D01*
X481250Y147027D01*
X480833Y146493D01*
X480542Y146253D01*
X480125Y146093D01*
X479750Y146040D01*
Y147160D01*
G01X481833Y148293D02*
X482083Y148453D01*
X482208Y148640D01*
X482250Y148853D01*
X482167Y149120D01*
X481958Y149307D01*
X481708Y149360D01*
X481458Y149333D01*
X481250Y149227D01*
X480833Y148693D01*
X480542Y148453D01*
X480125Y148293D01*
X479750Y148240D01*
Y149360D01*
G01X477713Y159542D02*
X477873Y159667D01*
X478060Y159750D01*
X478273D01*
X478513Y159625D01*
X478700Y159417D01*
X478833Y159167D01*
X478940Y158750D01*
X478967Y158375D01*
X478913Y158000D01*
X478833Y157750D01*
X478673Y157500D01*
X478487Y157333D01*
X478300Y157250D01*
X478113D01*
X477927Y157333D01*
X477767Y157458D01*
X477633Y157625D01*
G01X476100Y157250D02*
Y159750D01*
X476420Y159250D01*
G01Y157250D02*
X475780D01*
G01X474487Y157625D02*
X474327Y157417D01*
X474140Y157292D01*
X473900Y157250D01*
X473660Y157333D01*
X473473Y157500D01*
X473340Y157792D01*
X473313Y158125D01*
X473367Y158458D01*
X473500Y158667D01*
X473687Y158833D01*
X473873Y158875D01*
X474060Y158833D01*
X474300Y158667D01*
X474220Y159750D01*
X473500D01*
G01X471700Y157250D02*
Y159750D01*
X472020Y159250D01*
G01Y157250D02*
X471380D01*
G01X479042Y162787D02*
X479167Y162627D01*
X479250Y162440D01*
Y162227D01*
X479125Y161987D01*
X478917Y161800D01*
X478667Y161667D01*
X478250Y161560D01*
X477875Y161533D01*
X477500Y161587D01*
X477250Y161667D01*
X477000Y161827D01*
X476833Y162013D01*
X476750Y162200D01*
Y162387D01*
X476833Y162573D01*
X476958Y162733D01*
X477125Y162867D01*
G01X478833Y163893D02*
X479083Y164053D01*
X479208Y164240D01*
X479250Y164453D01*
X479167Y164720D01*
X478958Y164907D01*
X478708Y164960D01*
X478458Y164933D01*
X478250Y164827D01*
X477833Y164293D01*
X477542Y164053D01*
X477125Y163893D01*
X476750Y163840D01*
Y164960D01*
G01Y166600D02*
X479250D01*
X478750Y166280D01*
G01X476750D02*
Y166920D01*
G01X479250Y168800D02*
X479167Y168587D01*
X478958Y168427D01*
X478708Y168320D01*
X478375Y168240D01*
X478000Y168213D01*
X477625Y168240D01*
X477292Y168320D01*
X477042Y168427D01*
X476833Y168587D01*
X476750Y168800D01*
X476833Y169013D01*
X477042Y169173D01*
X477292Y169280D01*
X477625Y169360D01*
X478000Y169387D01*
X478375Y169360D01*
X478708Y169280D01*
X478958Y169173D01*
X479167Y169013D01*
X479250Y168800D01*
G01X479750Y161667D02*
X482250D01*
Y162333D01*
X482125Y162547D01*
X481958Y162680D01*
X481625Y162733D01*
X481292Y162680D01*
X481083Y162520D01*
X480958Y162333D01*
Y161667D01*
G01Y162333D02*
X479750Y162733D01*
G01X480125Y163813D02*
X479917Y163973D01*
X479792Y164160D01*
X479750Y164400D01*
X479833Y164640D01*
X480000Y164827D01*
X480292Y164960D01*
X480625Y164987D01*
X480958Y164933D01*
X481167Y164800D01*
X481333Y164613D01*
X481375Y164427D01*
X481333Y164240D01*
X481167Y164000D01*
X482250Y164080D01*
Y164800D01*
G01Y166600D02*
X482167Y166387D01*
X481958Y166227D01*
X481708Y166120D01*
X481375Y166040D01*
X481000Y166013D01*
X480625Y166040D01*
X480292Y166120D01*
X480042Y166227D01*
X479833Y166387D01*
X479750Y166600D01*
X479833Y166813D01*
X480042Y166973D01*
X480292Y167080D01*
X480625Y167160D01*
X481000Y167187D01*
X481375Y167160D01*
X481708Y167080D01*
X481958Y166973D01*
X482167Y166813D01*
X482250Y166600D01*
G01Y168800D02*
X482167Y168587D01*
X481958Y168427D01*
X481708Y168320D01*
X481375Y168240D01*
X481000Y168213D01*
X480625Y168240D01*
X480292Y168320D01*
X480042Y168427D01*
X479833Y168587D01*
X479750Y168800D01*
X479833Y169013D01*
X480042Y169173D01*
X480292Y169280D01*
X480625Y169360D01*
X481000Y169387D01*
X481375Y169360D01*
X481708Y169280D01*
X481958Y169173D01*
X482167Y169013D01*
X482250Y168800D01*
G01X478833Y170750D02*
Y173250D01*
X478167D01*
X477953Y173125D01*
X477820Y172958D01*
X477767Y172625D01*
X477820Y172292D01*
X477980Y172083D01*
X478167Y171958D01*
X478833D01*
G01X478167D02*
X477767Y170750D01*
G01X476687Y171125D02*
X476527Y170917D01*
X476340Y170792D01*
X476100Y170750D01*
X475860Y170833D01*
X475673Y171000D01*
X475540Y171292D01*
X475513Y171625D01*
X475567Y171958D01*
X475700Y172167D01*
X475887Y172333D01*
X476073Y172375D01*
X476260Y172333D01*
X476500Y172167D01*
X476420Y173250D01*
X475700D01*
G01X473900D02*
X474113Y173167D01*
X474273Y172958D01*
X474380Y172708D01*
X474460Y172375D01*
X474487Y172000D01*
X474460Y171625D01*
X474380Y171292D01*
X474273Y171042D01*
X474113Y170833D01*
X473900Y170750D01*
X473687Y170833D01*
X473527Y171042D01*
X473420Y171292D01*
X473340Y171625D01*
X473313Y172000D01*
X473340Y172375D01*
X473420Y172708D01*
X473527Y172958D01*
X473687Y173167D01*
X473900Y173250D01*
G01X471700Y170750D02*
Y173250D01*
X472020Y172750D01*
G01Y170750D02*
X471380D01*
G01X477713Y176542D02*
X477873Y176667D01*
X478060Y176750D01*
X478273D01*
X478513Y176625D01*
X478700Y176417D01*
X478833Y176167D01*
X478940Y175750D01*
X478967Y175375D01*
X478913Y175000D01*
X478833Y174750D01*
X478673Y174500D01*
X478487Y174333D01*
X478300Y174250D01*
X478113D01*
X477927Y174333D01*
X477767Y174458D01*
X477633Y174625D01*
G01X476100Y174250D02*
Y176750D01*
X476420Y176250D01*
G01Y174250D02*
X475780D01*
G01X474487Y174750D02*
X474327Y174458D01*
X474113Y174292D01*
X473873Y174250D01*
X473660Y174292D01*
X473447Y174500D01*
X473313Y174750D01*
X473287Y175000D01*
X473340Y175292D01*
X473527Y175500D01*
X473713Y175583D01*
X473953D01*
G01X473713D02*
X473553Y175708D01*
X473420Y175917D01*
X473367Y176167D01*
X473420Y176417D01*
X473553Y176625D01*
X473793Y176750D01*
X474033Y176708D01*
X474273Y176542D01*
G01X472153Y174542D02*
X471967Y174333D01*
X471753Y174250D01*
X471540Y174333D01*
X471353Y174583D01*
X471220Y174958D01*
X471167Y175333D01*
Y175792D01*
X471220Y176167D01*
X471353Y176500D01*
X471513Y176667D01*
X471700Y176750D01*
X471913Y176667D01*
X472073Y176500D01*
X472180Y176250D01*
X472233Y175917D01*
X472180Y175625D01*
X472047Y175333D01*
X471887Y175167D01*
X471700Y175125D01*
X471487Y175208D01*
X471327Y175417D01*
X471167Y175792D01*
G01X472542Y190287D02*
X472667Y190127D01*
X472750Y189940D01*
Y189727D01*
X472625Y189487D01*
X472417Y189300D01*
X472167Y189167D01*
X471750Y189060D01*
X471375Y189033D01*
X471000Y189087D01*
X470750Y189167D01*
X470500Y189327D01*
X470333Y189513D01*
X470250Y189700D01*
Y189887D01*
X470333Y190073D01*
X470458Y190233D01*
X470625Y190367D01*
G01X472333Y191393D02*
X472583Y191553D01*
X472708Y191740D01*
X472750Y191953D01*
X472667Y192220D01*
X472458Y192407D01*
X472208Y192460D01*
X471958Y192433D01*
X471750Y192327D01*
X471333Y191793D01*
X471042Y191553D01*
X470625Y191393D01*
X470250Y191340D01*
Y192460D01*
G01X472750Y194100D02*
X472667Y193887D01*
X472458Y193727D01*
X472208Y193620D01*
X471875Y193540D01*
X471500Y193513D01*
X471125Y193540D01*
X470792Y193620D01*
X470542Y193727D01*
X470333Y193887D01*
X470250Y194100D01*
X470333Y194313D01*
X470542Y194473D01*
X470792Y194580D01*
X471125Y194660D01*
X471500Y194687D01*
X471875Y194660D01*
X472208Y194580D01*
X472458Y194473D01*
X472667Y194313D01*
X472750Y194100D01*
G01X472333Y195793D02*
X472583Y195953D01*
X472708Y196140D01*
X472750Y196353D01*
X472667Y196620D01*
X472458Y196807D01*
X472208Y196860D01*
X471958Y196833D01*
X471750Y196727D01*
X471333Y196193D01*
X471042Y195953D01*
X470625Y195793D01*
X470250Y195740D01*
Y196860D01*
G01X473750Y189167D02*
X476250D01*
Y189833D01*
X476125Y190047D01*
X475958Y190180D01*
X475625Y190233D01*
X475292Y190180D01*
X475083Y190020D01*
X474958Y189833D01*
Y189167D01*
G01Y189833D02*
X473750Y190233D01*
G01X475833Y191393D02*
X476083Y191553D01*
X476208Y191740D01*
X476250Y191953D01*
X476167Y192220D01*
X475958Y192407D01*
X475708Y192460D01*
X475458Y192433D01*
X475250Y192327D01*
X474833Y191793D01*
X474542Y191553D01*
X474125Y191393D01*
X473750Y191340D01*
Y192460D01*
G01Y194047D02*
X474292Y194100D01*
X474750Y194180D01*
X475167Y194287D01*
X475625Y194420D01*
X476250Y194633D01*
Y193567D01*
G01X473750Y196300D02*
X476250D01*
X475750Y195980D01*
G01X473750D02*
Y196620D01*
G01X477213Y205042D02*
X477373Y205167D01*
X477560Y205250D01*
X477773D01*
X478013Y205125D01*
X478200Y204917D01*
X478333Y204667D01*
X478440Y204250D01*
X478467Y203875D01*
X478413Y203500D01*
X478333Y203250D01*
X478173Y203000D01*
X477987Y202833D01*
X477800Y202750D01*
X477613D01*
X477427Y202833D01*
X477267Y202958D01*
X477133Y203125D01*
G01X475600Y202750D02*
Y205250D01*
X475920Y204750D01*
G01Y202750D02*
X475280D01*
G01X473400Y205250D02*
X473613Y205167D01*
X473773Y204958D01*
X473880Y204708D01*
X473960Y204375D01*
X473987Y204000D01*
X473960Y203625D01*
X473880Y203292D01*
X473773Y203042D01*
X473613Y202833D01*
X473400Y202750D01*
X473187Y202833D01*
X473027Y203042D01*
X472920Y203292D01*
X472840Y203625D01*
X472813Y204000D01*
X472840Y204375D01*
X472920Y204708D01*
X473027Y204958D01*
X473187Y205167D01*
X473400Y205250D01*
G01X471787Y203250D02*
X471627Y202958D01*
X471413Y202792D01*
X471173Y202750D01*
X470960Y202792D01*
X470747Y203000D01*
X470613Y203250D01*
X470587Y203500D01*
X470640Y203792D01*
X470827Y204000D01*
X471013Y204083D01*
X471253D01*
G01X471013D02*
X470853Y204208D01*
X470720Y204417D01*
X470667Y204667D01*
X470720Y204917D01*
X470853Y205125D01*
X471093Y205250D01*
X471333Y205208D01*
X471573Y205042D01*
G01X469292Y223693D02*
X469447Y223463D01*
X469550Y223195D01*
Y222888D01*
X469395Y222543D01*
X469137Y222275D01*
X468827Y222083D01*
X468310Y221930D01*
X467845Y221892D01*
X467380Y221968D01*
X467070Y222083D01*
X466760Y222313D01*
X466553Y222582D01*
X466450Y222850D01*
Y223118D01*
X466553Y223387D01*
X466708Y223617D01*
X466915Y223808D01*
G01X466450Y225950D02*
X469550D01*
X468930Y225490D01*
G01X466450D02*
Y226410D01*
G01X466915Y228207D02*
X466657Y228437D01*
X466502Y228705D01*
X466450Y229050D01*
X466553Y229395D01*
X466760Y229663D01*
X467122Y229855D01*
X467535Y229893D01*
X467948Y229817D01*
X468207Y229625D01*
X468413Y229357D01*
X468465Y229088D01*
X468413Y228820D01*
X468207Y228475D01*
X469550Y228590D01*
Y229625D01*
G01X466450Y232610D02*
X469550D01*
X467328Y231192D01*
Y233108D01*
G01X470450Y222083D02*
X473550D01*
Y223042D01*
X473395Y223348D01*
X473188Y223540D01*
X472775Y223617D01*
X472362Y223540D01*
X472103Y223310D01*
X471948Y223042D01*
Y222083D01*
G01Y223042D02*
X470450Y223617D01*
G01X470915Y225107D02*
X470657Y225337D01*
X470502Y225605D01*
X470450Y225950D01*
X470553Y226295D01*
X470760Y226563D01*
X471122Y226755D01*
X471535Y226793D01*
X471948Y226717D01*
X472207Y226525D01*
X472413Y226257D01*
X472465Y225988D01*
X472413Y225720D01*
X472207Y225375D01*
X473550Y225490D01*
Y226525D01*
G01Y229050D02*
X473447Y228743D01*
X473188Y228513D01*
X472878Y228360D01*
X472465Y228245D01*
X472000Y228207D01*
X471535Y228245D01*
X471122Y228360D01*
X470812Y228513D01*
X470553Y228743D01*
X470450Y229050D01*
X470553Y229357D01*
X470812Y229587D01*
X471122Y229740D01*
X471535Y229855D01*
X472000Y229893D01*
X472465Y229855D01*
X472878Y229740D01*
X473188Y229587D01*
X473447Y229357D01*
X473550Y229050D01*
G01X470450Y232610D02*
X473550D01*
X471328Y231192D01*
Y233108D01*
G01X479417Y358450D02*
Y361550D01*
X478458D01*
X478152Y361395D01*
X477960Y361188D01*
X477883Y360775D01*
X477960Y360362D01*
X478190Y360103D01*
X478458Y359948D01*
X479417D01*
G01X478458D02*
X477883Y358450D01*
G01X475550D02*
Y361550D01*
X476010Y360930D01*
G01Y358450D02*
X475090D01*
G01X472450D02*
Y361550D01*
X472910Y360930D01*
G01Y358450D02*
X471990D01*
G01X470193Y358915D02*
X469963Y358657D01*
X469695Y358502D01*
X469350Y358450D01*
X469005Y358553D01*
X468737Y358760D01*
X468545Y359122D01*
X468507Y359535D01*
X468583Y359948D01*
X468775Y360207D01*
X469043Y360413D01*
X469312Y360465D01*
X469580Y360413D01*
X469925Y360207D01*
X469810Y361550D01*
X468775D01*
G01X499907Y119592D02*
X500137Y119747D01*
X500405Y119850D01*
X500712D01*
X501057Y119695D01*
X501325Y119437D01*
X501517Y119127D01*
X501670Y118610D01*
X501708Y118145D01*
X501632Y117680D01*
X501517Y117370D01*
X501287Y117060D01*
X501018Y116853D01*
X500750Y116750D01*
X500482D01*
X500213Y116853D01*
X499983Y117008D01*
X499792Y117215D01*
G01X497650Y116750D02*
Y119850D01*
X498110Y119230D01*
G01Y116750D02*
X497190D01*
G01X495278Y118042D02*
X495010Y118403D01*
X494780Y118610D01*
X494473Y118713D01*
X494205Y118610D01*
X494013Y118403D01*
X493860Y118093D01*
X493822Y117732D01*
X493860Y117422D01*
X494013Y117112D01*
X494243Y116853D01*
X494512Y116750D01*
X494818Y116853D01*
X495087Y117163D01*
X495240Y117628D01*
X495278Y118145D01*
X495202Y118817D01*
X495087Y119178D01*
X494895Y119540D01*
X494627Y119798D01*
X494358Y119850D01*
X494090Y119747D01*
X493898Y119488D01*
G01X491450Y116750D02*
X491182Y116802D01*
X490875Y116957D01*
X490683Y117215D01*
X490607Y117577D01*
X490683Y117938D01*
X490913Y118248D01*
X491258Y118403D01*
X491642D01*
X491872Y118507D01*
X492063Y118765D01*
X492140Y119127D01*
X492025Y119488D01*
X491757Y119747D01*
X491450Y119850D01*
X491143Y119747D01*
X490875Y119488D01*
X490760Y119127D01*
X490837Y118765D01*
X491028Y118507D01*
X491258Y118403D01*
X491642D01*
X491987Y118248D01*
X492217Y117938D01*
X492293Y117577D01*
X492217Y117215D01*
X492025Y116957D01*
X491718Y116802D01*
X491450Y116750D01*
G01X509417Y160950D02*
Y164050D01*
X508458D01*
X508152Y163895D01*
X507960Y163688D01*
X507883Y163275D01*
X507960Y162862D01*
X508190Y162603D01*
X508458Y162448D01*
X509417D01*
G01X508458D02*
X507883Y160950D01*
G01X506278Y163533D02*
X506048Y163843D01*
X505780Y163998D01*
X505473Y164050D01*
X505090Y163947D01*
X504822Y163688D01*
X504745Y163378D01*
X504783Y163068D01*
X504937Y162810D01*
X505703Y162293D01*
X506048Y161932D01*
X506278Y161415D01*
X506355Y160950D01*
X504745D01*
G01X502450D02*
Y164050D01*
X502910Y163430D01*
G01Y160950D02*
X501990D01*
G01X499427D02*
X499350Y161622D01*
X499235Y162190D01*
X499082Y162707D01*
X498890Y163275D01*
X498583Y164050D01*
X500117D01*
G01X485042Y176787D02*
X485167Y176627D01*
X485250Y176440D01*
Y176227D01*
X485125Y175987D01*
X484917Y175800D01*
X484667Y175667D01*
X484250Y175560D01*
X483875Y175533D01*
X483500Y175587D01*
X483250Y175667D01*
X483000Y175827D01*
X482833Y176013D01*
X482750Y176200D01*
Y176387D01*
X482833Y176573D01*
X482958Y176733D01*
X483125Y176867D01*
G01X482750Y178400D02*
X485250D01*
X484750Y178080D01*
G01X482750D02*
Y178720D01*
G01Y180920D02*
X485250D01*
X483458Y179933D01*
Y181267D01*
G01X483125Y182213D02*
X482917Y182373D01*
X482792Y182560D01*
X482750Y182800D01*
X482833Y183040D01*
X483000Y183227D01*
X483292Y183360D01*
X483625Y183387D01*
X483958Y183333D01*
X484167Y183200D01*
X484333Y183013D01*
X484375Y182827D01*
X484333Y182640D01*
X484167Y182400D01*
X485250Y182480D01*
Y183200D01*
G01X509417Y165450D02*
Y168550D01*
X508458D01*
X508152Y168395D01*
X507960Y168188D01*
X507883Y167775D01*
X507960Y167362D01*
X508190Y167103D01*
X508458Y166948D01*
X509417D01*
G01X508458D02*
X507883Y165450D01*
G01X506278Y168033D02*
X506048Y168343D01*
X505780Y168498D01*
X505473Y168550D01*
X505090Y168447D01*
X504822Y168188D01*
X504745Y167878D01*
X504783Y167568D01*
X504937Y167310D01*
X505703Y166793D01*
X506048Y166432D01*
X506278Y165915D01*
X506355Y165450D01*
X504745D01*
G01X502450D02*
Y168550D01*
X502910Y167930D01*
G01Y165450D02*
X501990D01*
G01X499350D02*
X499082Y165502D01*
X498775Y165657D01*
X498583Y165915D01*
X498507Y166277D01*
X498583Y166638D01*
X498813Y166948D01*
X499158Y167103D01*
X499542D01*
X499772Y167207D01*
X499963Y167465D01*
X500040Y167827D01*
X499925Y168188D01*
X499657Y168447D01*
X499350Y168550D01*
X499043Y168447D01*
X498775Y168188D01*
X498660Y167827D01*
X498737Y167465D01*
X498928Y167207D01*
X499158Y167103D01*
X499542D01*
X499887Y166948D01*
X500117Y166638D01*
X500193Y166277D01*
X500117Y165915D01*
X499925Y165657D01*
X499618Y165502D01*
X499350Y165450D01*
G01X508917Y195950D02*
Y199050D01*
X507958D01*
X507652Y198895D01*
X507460Y198688D01*
X507383Y198275D01*
X507460Y197862D01*
X507690Y197603D01*
X507958Y197448D01*
X508917D01*
G01X507958D02*
X507383Y195950D01*
G01X505778Y198533D02*
X505548Y198843D01*
X505280Y198998D01*
X504973Y199050D01*
X504590Y198947D01*
X504322Y198688D01*
X504245Y198378D01*
X504283Y198068D01*
X504437Y197810D01*
X505203Y197293D01*
X505548Y196932D01*
X505778Y196415D01*
X505855Y195950D01*
X504245D01*
G01X502678Y197242D02*
X502410Y197603D01*
X502180Y197810D01*
X501873Y197913D01*
X501605Y197810D01*
X501413Y197603D01*
X501260Y197293D01*
X501222Y196932D01*
X501260Y196622D01*
X501413Y196312D01*
X501643Y196053D01*
X501912Y195950D01*
X502218Y196053D01*
X502487Y196363D01*
X502640Y196828D01*
X502678Y197345D01*
X502602Y198017D01*
X502487Y198378D01*
X502295Y198740D01*
X502027Y198998D01*
X501758Y199050D01*
X501490Y198947D01*
X501298Y198688D01*
G01X499693Y196415D02*
X499463Y196157D01*
X499195Y196002D01*
X498850Y195950D01*
X498505Y196053D01*
X498237Y196260D01*
X498045Y196622D01*
X498007Y197035D01*
X498083Y197448D01*
X498275Y197707D01*
X498543Y197913D01*
X498812Y197965D01*
X499080Y197913D01*
X499425Y197707D01*
X499310Y199050D01*
X498275D01*
G01X508917Y200450D02*
Y203550D01*
X507958D01*
X507652Y203395D01*
X507460Y203188D01*
X507383Y202775D01*
X507460Y202362D01*
X507690Y202103D01*
X507958Y201948D01*
X508917D01*
G01X507958D02*
X507383Y200450D01*
G01X505778Y203033D02*
X505548Y203343D01*
X505280Y203498D01*
X504973Y203550D01*
X504590Y203447D01*
X504322Y203188D01*
X504245Y202878D01*
X504283Y202568D01*
X504437Y202310D01*
X505203Y201793D01*
X505548Y201432D01*
X505778Y200915D01*
X505855Y200450D01*
X504245D01*
G01X502678Y201742D02*
X502410Y202103D01*
X502180Y202310D01*
X501873Y202413D01*
X501605Y202310D01*
X501413Y202103D01*
X501260Y201793D01*
X501222Y201432D01*
X501260Y201122D01*
X501413Y200812D01*
X501643Y200553D01*
X501912Y200450D01*
X502218Y200553D01*
X502487Y200863D01*
X502640Y201328D01*
X502678Y201845D01*
X502602Y202517D01*
X502487Y202878D01*
X502295Y203240D01*
X502027Y203498D01*
X501758Y203550D01*
X501490Y203447D01*
X501298Y203188D01*
G01X498390Y200450D02*
Y203550D01*
X499808Y201328D01*
X497892D01*
G01X505307Y253792D02*
X505537Y253947D01*
X505805Y254050D01*
X506112D01*
X506457Y253895D01*
X506725Y253637D01*
X506917Y253327D01*
X507070Y252810D01*
X507108Y252345D01*
X507032Y251880D01*
X506917Y251570D01*
X506687Y251260D01*
X506418Y251053D01*
X506150Y250950D01*
X505882D01*
X505613Y251053D01*
X505383Y251208D01*
X505192Y251415D01*
G01X503050Y250950D02*
Y254050D01*
X503510Y253430D01*
G01Y250950D02*
X502590D01*
G01X499950D02*
X499682Y251002D01*
X499375Y251157D01*
X499183Y251415D01*
X499107Y251777D01*
X499183Y252138D01*
X499413Y252448D01*
X499758Y252603D01*
X500142D01*
X500372Y252707D01*
X500563Y252965D01*
X500640Y253327D01*
X500525Y253688D01*
X500257Y253947D01*
X499950Y254050D01*
X499643Y253947D01*
X499375Y253688D01*
X499260Y253327D01*
X499337Y252965D01*
X499528Y252707D01*
X499758Y252603D01*
X500142D01*
X500487Y252448D01*
X500717Y252138D01*
X500793Y251777D01*
X500717Y251415D01*
X500525Y251157D01*
X500218Y251002D01*
X499950Y250950D01*
G01X496850D02*
Y254050D01*
X497310Y253430D01*
G01Y250950D02*
X496390D01*
G01X489450Y258583D02*
X492550D01*
Y259542D01*
X492395Y259848D01*
X492188Y260040D01*
X491775Y260117D01*
X491362Y260040D01*
X491103Y259810D01*
X490948Y259542D01*
Y258583D01*
G01Y259542D02*
X489450Y260117D01*
G01Y262450D02*
X492550D01*
X491930Y261990D01*
G01X489450D02*
Y262910D01*
G01Y265473D02*
X490122Y265550D01*
X490690Y265665D01*
X491207Y265818D01*
X491775Y266010D01*
X492550Y266317D01*
Y264783D01*
G01X489450Y269110D02*
X492550D01*
X490328Y267692D01*
Y269608D01*
G01X487450Y361583D02*
X490550D01*
Y362542D01*
X490395Y362848D01*
X490188Y363040D01*
X489775Y363117D01*
X489362Y363040D01*
X489103Y362810D01*
X488948Y362542D01*
Y361583D01*
G01Y362542D02*
X487450Y363117D01*
G01Y365450D02*
X490550D01*
X489930Y364990D01*
G01X487450D02*
Y365910D01*
G01Y368550D02*
X490550D01*
X489930Y368090D01*
G01X487450D02*
Y369010D01*
G01Y371650D02*
X490550D01*
X489930Y371190D01*
G01X487450D02*
Y372110D01*
G01X496950Y358083D02*
X500050D01*
Y359042D01*
X499895Y359348D01*
X499688Y359540D01*
X499275Y359617D01*
X498862Y359540D01*
X498603Y359310D01*
X498448Y359042D01*
Y358083D01*
G01Y359042D02*
X496950Y359617D01*
G01Y361950D02*
X500050D01*
X499430Y361490D01*
G01X496950D02*
Y362410D01*
G01X500050Y365050D02*
X499947Y364743D01*
X499688Y364513D01*
X499378Y364360D01*
X498965Y364245D01*
X498500Y364207D01*
X498035Y364245D01*
X497622Y364360D01*
X497312Y364513D01*
X497053Y364743D01*
X496950Y365050D01*
X497053Y365357D01*
X497312Y365587D01*
X497622Y365740D01*
X498035Y365855D01*
X498500Y365893D01*
X498965Y365855D01*
X499378Y365740D01*
X499688Y365587D01*
X499947Y365357D01*
X500050Y365050D01*
G01X497312Y367498D02*
X497053Y367767D01*
X496950Y368073D01*
X497053Y368380D01*
X497363Y368648D01*
X497828Y368840D01*
X498293Y368917D01*
X498862D01*
X499327Y368840D01*
X499740Y368648D01*
X499947Y368418D01*
X500050Y368150D01*
X499947Y367843D01*
X499740Y367613D01*
X499430Y367460D01*
X499017Y367383D01*
X498655Y367460D01*
X498293Y367652D01*
X498087Y367882D01*
X498035Y368150D01*
X498138Y368457D01*
X498397Y368687D01*
X498862Y368917D01*
G01X492450Y361583D02*
X495550D01*
Y362542D01*
X495395Y362848D01*
X495188Y363040D01*
X494775Y363117D01*
X494362Y363040D01*
X494103Y362810D01*
X493948Y362542D01*
Y361583D01*
G01Y362542D02*
X492450Y363117D01*
G01Y365450D02*
X495550D01*
X494930Y364990D01*
G01X492450D02*
Y365910D01*
G01Y368550D02*
X495550D01*
X494930Y368090D01*
G01X492450D02*
Y369010D01*
G01X495550Y371650D02*
X495447Y371343D01*
X495188Y371113D01*
X494878Y370960D01*
X494465Y370845D01*
X494000Y370807D01*
X493535Y370845D01*
X493122Y370960D01*
X492812Y371113D01*
X492553Y371343D01*
X492450Y371650D01*
X492553Y371957D01*
X492812Y372187D01*
X493122Y372340D01*
X493535Y372455D01*
X494000Y372493D01*
X494465Y372455D01*
X494878Y372340D01*
X495188Y372187D01*
X495447Y371957D01*
X495550Y371650D01*
G01X510417Y174450D02*
Y177550D01*
X509458D01*
X509152Y177395D01*
X508960Y177188D01*
X508883Y176775D01*
X508960Y176362D01*
X509190Y176103D01*
X509458Y175948D01*
X510417D01*
G01X509458D02*
X508883Y174450D01*
G01X507278Y177033D02*
X507048Y177343D01*
X506780Y177498D01*
X506473Y177550D01*
X506090Y177447D01*
X505822Y177188D01*
X505745Y176878D01*
X505783Y176568D01*
X505937Y176310D01*
X506703Y175793D01*
X507048Y175432D01*
X507278Y174915D01*
X507355Y174450D01*
X505745D01*
G01X503450Y177550D02*
X503757Y177447D01*
X503987Y177188D01*
X504140Y176878D01*
X504255Y176465D01*
X504293Y176000D01*
X504255Y175535D01*
X504140Y175122D01*
X503987Y174812D01*
X503757Y174553D01*
X503450Y174450D01*
X503143Y174553D01*
X502913Y174812D01*
X502760Y175122D01*
X502645Y175535D01*
X502607Y176000D01*
X502645Y176465D01*
X502760Y176878D01*
X502913Y177188D01*
X503143Y177447D01*
X503450Y177550D01*
G01X501002Y174812D02*
X500733Y174553D01*
X500427Y174450D01*
X500120Y174553D01*
X499852Y174863D01*
X499660Y175328D01*
X499583Y175793D01*
Y176362D01*
X499660Y176827D01*
X499852Y177240D01*
X500082Y177447D01*
X500350Y177550D01*
X500657Y177447D01*
X500887Y177240D01*
X501040Y176930D01*
X501117Y176517D01*
X501040Y176155D01*
X500848Y175793D01*
X500618Y175587D01*
X500350Y175535D01*
X500043Y175638D01*
X499813Y175897D01*
X499583Y176362D01*
G01X510417Y178950D02*
Y182050D01*
X509458D01*
X509152Y181895D01*
X508960Y181688D01*
X508883Y181275D01*
X508960Y180862D01*
X509190Y180603D01*
X509458Y180448D01*
X510417D01*
G01X509458D02*
X508883Y178950D01*
G01X506550D02*
Y182050D01*
X507010Y181430D01*
G01Y178950D02*
X506090D01*
G01X504102Y179312D02*
X503833Y179053D01*
X503527Y178950D01*
X503220Y179053D01*
X502952Y179363D01*
X502760Y179828D01*
X502683Y180293D01*
Y180862D01*
X502760Y181327D01*
X502952Y181740D01*
X503182Y181947D01*
X503450Y182050D01*
X503757Y181947D01*
X503987Y181740D01*
X504140Y181430D01*
X504217Y181017D01*
X504140Y180655D01*
X503948Y180293D01*
X503718Y180087D01*
X503450Y180035D01*
X503143Y180138D01*
X502913Y180397D01*
X502683Y180862D01*
G01X501193Y179415D02*
X500963Y179157D01*
X500695Y179002D01*
X500350Y178950D01*
X500005Y179053D01*
X499737Y179260D01*
X499545Y179622D01*
X499507Y180035D01*
X499583Y180448D01*
X499775Y180707D01*
X500043Y180913D01*
X500312Y180965D01*
X500580Y180913D01*
X500925Y180707D01*
X500810Y182050D01*
X499775D01*
G01X510367Y183450D02*
Y186550D01*
X509408D01*
X509102Y186395D01*
X508910Y186188D01*
X508833Y185775D01*
X508910Y185362D01*
X509140Y185103D01*
X509408Y184948D01*
X510367D01*
G01X509408D02*
X508833Y183450D01*
G01X507152Y183812D02*
X506883Y183553D01*
X506577Y183450D01*
X506270Y183553D01*
X506002Y183863D01*
X505810Y184328D01*
X505733Y184793D01*
Y185362D01*
X505810Y185827D01*
X506002Y186240D01*
X506232Y186447D01*
X506500Y186550D01*
X506807Y186447D01*
X507037Y186240D01*
X507190Y185930D01*
X507267Y185517D01*
X507190Y185155D01*
X506998Y184793D01*
X506768Y184587D01*
X506500Y184535D01*
X506193Y184638D01*
X505963Y184897D01*
X505733Y185362D01*
G01X504128Y186033D02*
X503898Y186343D01*
X503630Y186498D01*
X503323Y186550D01*
X502940Y186447D01*
X502672Y186188D01*
X502595Y185878D01*
X502633Y185568D01*
X502787Y185310D01*
X503553Y184793D01*
X503898Y184432D01*
X504128Y183915D01*
X504205Y183450D01*
X502595D01*
G01X517417Y343450D02*
Y346550D01*
X516458D01*
X516152Y346395D01*
X515960Y346188D01*
X515883Y345775D01*
X515960Y345362D01*
X516190Y345103D01*
X516458Y344948D01*
X517417D01*
G01X516458D02*
X515883Y343450D01*
G01X514278Y346033D02*
X514048Y346343D01*
X513780Y346498D01*
X513473Y346550D01*
X513090Y346447D01*
X512822Y346188D01*
X512745Y345878D01*
X512783Y345568D01*
X512937Y345310D01*
X513703Y344793D01*
X514048Y344432D01*
X514278Y343915D01*
X514355Y343450D01*
X512745D01*
G01X511178Y344742D02*
X510910Y345103D01*
X510680Y345310D01*
X510373Y345413D01*
X510105Y345310D01*
X509913Y345103D01*
X509760Y344793D01*
X509722Y344432D01*
X509760Y344122D01*
X509913Y343812D01*
X510143Y343553D01*
X510412Y343450D01*
X510718Y343553D01*
X510987Y343863D01*
X511140Y344328D01*
X511178Y344845D01*
X511102Y345517D01*
X510987Y345878D01*
X510795Y346240D01*
X510527Y346498D01*
X510258Y346550D01*
X509990Y346447D01*
X509798Y346188D01*
G01X508002Y343812D02*
X507733Y343553D01*
X507427Y343450D01*
X507120Y343553D01*
X506852Y343863D01*
X506660Y344328D01*
X506583Y344793D01*
Y345362D01*
X506660Y345827D01*
X506852Y346240D01*
X507082Y346447D01*
X507350Y346550D01*
X507657Y346447D01*
X507887Y346240D01*
X508040Y345930D01*
X508117Y345517D01*
X508040Y345155D01*
X507848Y344793D01*
X507618Y344587D01*
X507350Y344535D01*
X507043Y344638D01*
X506813Y344897D01*
X506583Y345362D01*
G01X510292Y374743D02*
X510447Y374513D01*
X510550Y374245D01*
Y373938D01*
X510395Y373593D01*
X510137Y373325D01*
X509827Y373133D01*
X509310Y372980D01*
X508845Y372942D01*
X508380Y373018D01*
X508070Y373133D01*
X507760Y373363D01*
X507553Y373632D01*
X507450Y373900D01*
Y374168D01*
X507553Y374437D01*
X507708Y374667D01*
X507915Y374858D01*
G01X507450Y376923D02*
X508122Y377000D01*
X508690Y377115D01*
X509207Y377268D01*
X509775Y377460D01*
X510550Y377767D01*
Y376233D01*
G01X508070Y379257D02*
X507708Y379487D01*
X507502Y379793D01*
X507450Y380138D01*
X507502Y380445D01*
X507760Y380752D01*
X508070Y380943D01*
X508380Y380982D01*
X508742Y380905D01*
X509000Y380637D01*
X509103Y380368D01*
Y380023D01*
G01Y380368D02*
X509258Y380598D01*
X509517Y380790D01*
X509827Y380867D01*
X510137Y380790D01*
X510395Y380598D01*
X510550Y380253D01*
X510498Y379908D01*
X510292Y379563D01*
G01X503292Y374243D02*
X503447Y374013D01*
X503550Y373745D01*
Y373438D01*
X503395Y373093D01*
X503137Y372825D01*
X502827Y372633D01*
X502310Y372480D01*
X501845Y372442D01*
X501380Y372518D01*
X501070Y372633D01*
X500760Y372863D01*
X500553Y373132D01*
X500450Y373400D01*
Y373668D01*
X500553Y373937D01*
X500708Y374167D01*
X500915Y374358D01*
G01X500450Y376423D02*
X501122Y376500D01*
X501690Y376615D01*
X502207Y376768D01*
X502775Y376960D01*
X503550Y377267D01*
Y375733D01*
G01X500450Y379600D02*
X500502Y379868D01*
X500657Y380175D01*
X500915Y380367D01*
X501277Y380443D01*
X501638Y380367D01*
X501948Y380137D01*
X502103Y379792D01*
Y379408D01*
X502207Y379178D01*
X502465Y378987D01*
X502827Y378910D01*
X503188Y379025D01*
X503447Y379293D01*
X503550Y379600D01*
X503447Y379907D01*
X503188Y380175D01*
X502827Y380290D01*
X502465Y380213D01*
X502207Y380022D01*
X502103Y379792D01*
Y379408D01*
X501948Y379063D01*
X501638Y378833D01*
X501277Y378757D01*
X500915Y378833D01*
X500657Y379025D01*
X500502Y379332D01*
X500450Y379600D01*
G01X542417Y56950D02*
Y60050D01*
X541458D01*
X541152Y59895D01*
X540960Y59688D01*
X540883Y59275D01*
X540960Y58862D01*
X541190Y58603D01*
X541458Y58448D01*
X542417D01*
G01X541458D02*
X540883Y56950D01*
G01X539278Y59533D02*
X539048Y59843D01*
X538780Y59998D01*
X538473Y60050D01*
X538090Y59947D01*
X537822Y59688D01*
X537745Y59378D01*
X537783Y59068D01*
X537937Y58810D01*
X538703Y58293D01*
X539048Y57932D01*
X539278Y57415D01*
X539355Y56950D01*
X537745D01*
G01X536293Y57570D02*
X536063Y57208D01*
X535757Y57002D01*
X535412Y56950D01*
X535105Y57002D01*
X534798Y57260D01*
X534607Y57570D01*
X534568Y57880D01*
X534645Y58242D01*
X534913Y58500D01*
X535182Y58603D01*
X535527D01*
G01X535182D02*
X534952Y58758D01*
X534760Y59017D01*
X534683Y59327D01*
X534760Y59637D01*
X534952Y59895D01*
X535297Y60050D01*
X535642Y59998D01*
X535987Y59792D01*
G01X532350Y60050D02*
X532657Y59947D01*
X532887Y59688D01*
X533040Y59378D01*
X533155Y58965D01*
X533193Y58500D01*
X533155Y58035D01*
X533040Y57622D01*
X532887Y57312D01*
X532657Y57053D01*
X532350Y56950D01*
X532043Y57053D01*
X531813Y57312D01*
X531660Y57622D01*
X531545Y58035D01*
X531507Y58500D01*
X531545Y58965D01*
X531660Y59378D01*
X531813Y59688D01*
X532043Y59947D01*
X532350Y60050D01*
G01X542917Y71950D02*
Y75050D01*
X541958D01*
X541652Y74895D01*
X541460Y74688D01*
X541383Y74275D01*
X541460Y73862D01*
X541690Y73603D01*
X541958Y73448D01*
X542917D01*
G01X541958D02*
X541383Y71950D01*
G01X539778Y74533D02*
X539548Y74843D01*
X539280Y74998D01*
X538973Y75050D01*
X538590Y74947D01*
X538322Y74688D01*
X538245Y74378D01*
X538283Y74068D01*
X538437Y73810D01*
X539203Y73293D01*
X539548Y72932D01*
X539778Y72415D01*
X539855Y71950D01*
X538245D01*
G01X536793Y72570D02*
X536563Y72208D01*
X536257Y72002D01*
X535912Y71950D01*
X535605Y72002D01*
X535298Y72260D01*
X535107Y72570D01*
X535068Y72880D01*
X535145Y73242D01*
X535413Y73500D01*
X535682Y73603D01*
X536027D01*
G01X535682D02*
X535452Y73758D01*
X535260Y74017D01*
X535183Y74327D01*
X535260Y74637D01*
X535452Y74895D01*
X535797Y75050D01*
X536142Y74998D01*
X536487Y74792D01*
G01X533693Y72570D02*
X533463Y72208D01*
X533157Y72002D01*
X532812Y71950D01*
X532505Y72002D01*
X532198Y72260D01*
X532007Y72570D01*
X531968Y72880D01*
X532045Y73242D01*
X532313Y73500D01*
X532582Y73603D01*
X532927D01*
G01X532582D02*
X532352Y73758D01*
X532160Y74017D01*
X532083Y74327D01*
X532160Y74637D01*
X532352Y74895D01*
X532697Y75050D01*
X533042Y74998D01*
X533387Y74792D01*
G01X518950Y257583D02*
X522050D01*
Y258542D01*
X521895Y258848D01*
X521688Y259040D01*
X521275Y259117D01*
X520862Y259040D01*
X520603Y258810D01*
X520448Y258542D01*
Y257583D01*
G01Y258542D02*
X518950Y259117D01*
G01Y261450D02*
X522050D01*
X521430Y260990D01*
G01X518950D02*
Y261910D01*
G01Y264550D02*
X519002Y264818D01*
X519157Y265125D01*
X519415Y265317D01*
X519777Y265393D01*
X520138Y265317D01*
X520448Y265087D01*
X520603Y264742D01*
Y264358D01*
X520707Y264128D01*
X520965Y263937D01*
X521327Y263860D01*
X521688Y263975D01*
X521947Y264243D01*
X522050Y264550D01*
X521947Y264857D01*
X521688Y265125D01*
X521327Y265240D01*
X520965Y265163D01*
X520707Y264972D01*
X520603Y264742D01*
Y264358D01*
X520448Y264013D01*
X520138Y263783D01*
X519777Y263707D01*
X519415Y263783D01*
X519157Y263975D01*
X519002Y264282D01*
X518950Y264550D01*
G01Y267650D02*
X519002Y267918D01*
X519157Y268225D01*
X519415Y268417D01*
X519777Y268493D01*
X520138Y268417D01*
X520448Y268187D01*
X520603Y267842D01*
Y267458D01*
X520707Y267228D01*
X520965Y267037D01*
X521327Y266960D01*
X521688Y267075D01*
X521947Y267343D01*
X522050Y267650D01*
X521947Y267957D01*
X521688Y268225D01*
X521327Y268340D01*
X520965Y268263D01*
X520707Y268072D01*
X520603Y267842D01*
Y267458D01*
X520448Y267113D01*
X520138Y266883D01*
X519777Y266807D01*
X519415Y266883D01*
X519157Y267075D01*
X519002Y267382D01*
X518950Y267650D01*
G01X524950Y277583D02*
X528050D01*
Y278542D01*
X527895Y278848D01*
X527688Y279040D01*
X527275Y279117D01*
X526862Y279040D01*
X526603Y278810D01*
X526448Y278542D01*
Y277583D01*
G01Y278542D02*
X524950Y279117D01*
G01Y281910D02*
X528050D01*
X525828Y280492D01*
Y282408D01*
G01X528050Y284550D02*
X527947Y284243D01*
X527688Y284013D01*
X527378Y283860D01*
X526965Y283745D01*
X526500Y283707D01*
X526035Y283745D01*
X525622Y283860D01*
X525312Y284013D01*
X525053Y284243D01*
X524950Y284550D01*
X525053Y284857D01*
X525312Y285087D01*
X525622Y285240D01*
X526035Y285355D01*
X526500Y285393D01*
X526965Y285355D01*
X527378Y285240D01*
X527688Y285087D01*
X527947Y284857D01*
X528050Y284550D01*
G01X525570Y286807D02*
X525208Y287037D01*
X525002Y287343D01*
X524950Y287688D01*
X525002Y287995D01*
X525260Y288302D01*
X525570Y288493D01*
X525880Y288532D01*
X526242Y288455D01*
X526500Y288187D01*
X526603Y287918D01*
Y287573D01*
G01Y287918D02*
X526758Y288148D01*
X527017Y288340D01*
X527327Y288417D01*
X527637Y288340D01*
X527895Y288148D01*
X528050Y287803D01*
X527998Y287458D01*
X527792Y287113D01*
G01X537917Y272950D02*
Y276050D01*
X536958D01*
X536652Y275895D01*
X536460Y275688D01*
X536383Y275275D01*
X536460Y274862D01*
X536690Y274603D01*
X536958Y274448D01*
X537917D01*
G01X536958D02*
X536383Y272950D01*
G01X534050D02*
Y276050D01*
X534510Y275430D01*
G01Y272950D02*
X533590D01*
G01X531793Y273570D02*
X531563Y273208D01*
X531257Y273002D01*
X530912Y272950D01*
X530605Y273002D01*
X530298Y273260D01*
X530107Y273570D01*
X530068Y273880D01*
X530145Y274242D01*
X530413Y274500D01*
X530682Y274603D01*
X531027D01*
G01X530682D02*
X530452Y274758D01*
X530260Y275017D01*
X530183Y275327D01*
X530260Y275637D01*
X530452Y275895D01*
X530797Y276050D01*
X531142Y275998D01*
X531487Y275792D01*
G01X528693Y273570D02*
X528463Y273208D01*
X528157Y273002D01*
X527812Y272950D01*
X527505Y273002D01*
X527198Y273260D01*
X527007Y273570D01*
X526968Y273880D01*
X527045Y274242D01*
X527313Y274500D01*
X527582Y274603D01*
X527927D01*
G01X527582D02*
X527352Y274758D01*
X527160Y275017D01*
X527083Y275327D01*
X527160Y275637D01*
X527352Y275895D01*
X527697Y276050D01*
X528042Y275998D01*
X528387Y275792D01*
G01X539917Y276950D02*
Y280050D01*
X538958D01*
X538652Y279895D01*
X538460Y279688D01*
X538383Y279275D01*
X538460Y278862D01*
X538690Y278603D01*
X538958Y278448D01*
X539917D01*
G01X538958D02*
X538383Y276950D01*
G01X536050D02*
Y280050D01*
X536510Y279430D01*
G01Y276950D02*
X535590D01*
G01X533793Y277570D02*
X533563Y277208D01*
X533257Y277002D01*
X532912Y276950D01*
X532605Y277002D01*
X532298Y277260D01*
X532107Y277570D01*
X532068Y277880D01*
X532145Y278242D01*
X532413Y278500D01*
X532682Y278603D01*
X533027D01*
G01X532682D02*
X532452Y278758D01*
X532260Y279017D01*
X532183Y279327D01*
X532260Y279637D01*
X532452Y279895D01*
X532797Y280050D01*
X533142Y279998D01*
X533487Y279792D01*
G01X530693Y277415D02*
X530463Y277157D01*
X530195Y277002D01*
X529850Y276950D01*
X529505Y277053D01*
X529237Y277260D01*
X529045Y277622D01*
X529007Y278035D01*
X529083Y278448D01*
X529275Y278707D01*
X529543Y278913D01*
X529812Y278965D01*
X530080Y278913D01*
X530425Y278707D01*
X530310Y280050D01*
X529275D01*
G01X539867Y280950D02*
Y284050D01*
X538908D01*
X538602Y283895D01*
X538410Y283688D01*
X538333Y283275D01*
X538410Y282862D01*
X538640Y282603D01*
X538908Y282448D01*
X539867D01*
G01X538908D02*
X538333Y280950D01*
G01X535540D02*
Y284050D01*
X536958Y281828D01*
X535042D01*
G01X533628Y283533D02*
X533398Y283843D01*
X533130Y283998D01*
X532823Y284050D01*
X532440Y283947D01*
X532172Y283688D01*
X532095Y283378D01*
X532133Y283068D01*
X532287Y282810D01*
X533053Y282293D01*
X533398Y281932D01*
X533628Y281415D01*
X533705Y280950D01*
X532095D01*
G01X536917Y291450D02*
Y294550D01*
X535958D01*
X535652Y294395D01*
X535460Y294188D01*
X535383Y293775D01*
X535460Y293362D01*
X535690Y293103D01*
X535958Y292948D01*
X536917D01*
G01X535958D02*
X535383Y291450D01*
G01X532590D02*
Y294550D01*
X534008Y292328D01*
X532092D01*
G01X529950Y294550D02*
X530257Y294447D01*
X530487Y294188D01*
X530640Y293878D01*
X530755Y293465D01*
X530793Y293000D01*
X530755Y292535D01*
X530640Y292122D01*
X530487Y291812D01*
X530257Y291553D01*
X529950Y291450D01*
X529643Y291553D01*
X529413Y291812D01*
X529260Y292122D01*
X529145Y292535D01*
X529107Y293000D01*
X529145Y293465D01*
X529260Y293878D01*
X529413Y294188D01*
X529643Y294447D01*
X529950Y294550D01*
G01X526390Y291450D02*
Y294550D01*
X527808Y292328D01*
X525892D01*
G01X530958Y340950D02*
X530000Y344050D01*
X529042Y340950D01*
G01X529387Y342035D02*
X530613D01*
G01X521292Y360343D02*
X521447Y360113D01*
X521550Y359845D01*
Y359538D01*
X521395Y359193D01*
X521137Y358925D01*
X520827Y358733D01*
X520310Y358580D01*
X519845Y358542D01*
X519380Y358618D01*
X519070Y358733D01*
X518760Y358963D01*
X518553Y359232D01*
X518450Y359500D01*
Y359768D01*
X518553Y360037D01*
X518708Y360267D01*
X518915Y360458D01*
G01X518450Y361833D02*
X521550D01*
Y362792D01*
X521395Y363098D01*
X521188Y363290D01*
X520775Y363367D01*
X520362Y363290D01*
X520103Y363060D01*
X519948Y362792D01*
Y361833D01*
G01Y362792D02*
X518450Y363367D01*
G01X519070Y364857D02*
X518708Y365087D01*
X518502Y365393D01*
X518450Y365738D01*
X518502Y366045D01*
X518760Y366352D01*
X519070Y366543D01*
X519380Y366582D01*
X519742Y366505D01*
X520000Y366237D01*
X520103Y365968D01*
Y365623D01*
G01Y365968D02*
X520258Y366198D01*
X520517Y366390D01*
X520827Y366467D01*
X521137Y366390D01*
X521395Y366198D01*
X521550Y365853D01*
X521498Y365508D01*
X521292Y365163D01*
G01X530450Y382083D02*
X533550D01*
Y383042D01*
X533395Y383348D01*
X533188Y383540D01*
X532775Y383617D01*
X532362Y383540D01*
X532103Y383310D01*
X531948Y383042D01*
Y382083D01*
G01Y383042D02*
X530450Y383617D01*
G01X533033Y385222D02*
X533343Y385452D01*
X533498Y385720D01*
X533550Y386027D01*
X533447Y386410D01*
X533188Y386678D01*
X532878Y386755D01*
X532568Y386717D01*
X532310Y386563D01*
X531793Y385797D01*
X531432Y385452D01*
X530915Y385222D01*
X530450Y385145D01*
Y386755D01*
G01Y389050D02*
X533550D01*
X532930Y388590D01*
G01X530450D02*
Y389510D01*
G01X533550Y392150D02*
X533447Y391843D01*
X533188Y391613D01*
X532878Y391460D01*
X532465Y391345D01*
X532000Y391307D01*
X531535Y391345D01*
X531122Y391460D01*
X530812Y391613D01*
X530553Y391843D01*
X530450Y392150D01*
X530553Y392457D01*
X530812Y392687D01*
X531122Y392840D01*
X531535Y392955D01*
X532000Y392993D01*
X532465Y392955D01*
X532878Y392840D01*
X533188Y392687D01*
X533447Y392457D01*
X533550Y392150D01*
G01X547292Y161693D02*
X547447Y161463D01*
X547550Y161195D01*
Y160888D01*
X547395Y160543D01*
X547137Y160275D01*
X546827Y160083D01*
X546310Y159930D01*
X545845Y159892D01*
X545380Y159968D01*
X545070Y160083D01*
X544760Y160313D01*
X544553Y160582D01*
X544450Y160850D01*
Y161118D01*
X544553Y161387D01*
X544708Y161617D01*
X544915Y161808D01*
G01X544450Y163950D02*
X547550D01*
X546930Y163490D01*
G01X544450D02*
Y164410D01*
G01Y166973D02*
X545122Y167050D01*
X545690Y167165D01*
X546207Y167318D01*
X546775Y167510D01*
X547550Y167817D01*
Y166283D01*
G01X544450Y170150D02*
X544502Y170418D01*
X544657Y170725D01*
X544915Y170917D01*
X545277Y170993D01*
X545638Y170917D01*
X545948Y170687D01*
X546103Y170342D01*
Y169958D01*
X546207Y169728D01*
X546465Y169537D01*
X546827Y169460D01*
X547188Y169575D01*
X547447Y169843D01*
X547550Y170150D01*
X547447Y170457D01*
X547188Y170725D01*
X546827Y170840D01*
X546465Y170763D01*
X546207Y170572D01*
X546103Y170342D01*
Y169958D01*
X545948Y169613D01*
X545638Y169383D01*
X545277Y169307D01*
X544915Y169383D01*
X544657Y169575D01*
X544502Y169882D01*
X544450Y170150D01*
G01X548842Y178193D02*
X548997Y177963D01*
X549100Y177695D01*
Y177388D01*
X548945Y177043D01*
X548687Y176775D01*
X548377Y176583D01*
X547860Y176430D01*
X547395Y176392D01*
X546930Y176468D01*
X546620Y176583D01*
X546310Y176813D01*
X546103Y177082D01*
X546000Y177350D01*
Y177618D01*
X546103Y177887D01*
X546258Y178117D01*
X546465Y178308D01*
G01X546000Y180450D02*
X549100D01*
X548480Y179990D01*
G01X546000D02*
Y180910D01*
G01Y183473D02*
X546672Y183550D01*
X547240Y183665D01*
X547757Y183818D01*
X548325Y184010D01*
X549100Y184317D01*
Y182783D01*
G01X546362Y185998D02*
X546103Y186267D01*
X546000Y186573D01*
X546103Y186880D01*
X546413Y187148D01*
X546878Y187340D01*
X547343Y187417D01*
X547912D01*
X548377Y187340D01*
X548790Y187148D01*
X548997Y186918D01*
X549100Y186650D01*
X548997Y186343D01*
X548790Y186113D01*
X548480Y185960D01*
X548067Y185883D01*
X547705Y185960D01*
X547343Y186152D01*
X547137Y186382D01*
X547085Y186650D01*
X547188Y186957D01*
X547447Y187187D01*
X547912Y187417D01*
G01X547792Y192693D02*
X547947Y192463D01*
X548050Y192195D01*
Y191888D01*
X547895Y191543D01*
X547637Y191275D01*
X547327Y191083D01*
X546810Y190930D01*
X546345Y190892D01*
X545880Y190968D01*
X545570Y191083D01*
X545260Y191313D01*
X545053Y191582D01*
X544950Y191850D01*
Y192118D01*
X545053Y192387D01*
X545208Y192617D01*
X545415Y192808D01*
G01X547533Y194222D02*
X547843Y194452D01*
X547998Y194720D01*
X548050Y195027D01*
X547947Y195410D01*
X547688Y195678D01*
X547378Y195755D01*
X547068Y195717D01*
X546810Y195563D01*
X546293Y194797D01*
X545932Y194452D01*
X545415Y194222D01*
X544950Y194145D01*
Y195755D01*
G01X546242Y197322D02*
X546603Y197590D01*
X546810Y197820D01*
X546913Y198127D01*
X546810Y198395D01*
X546603Y198587D01*
X546293Y198740D01*
X545932Y198778D01*
X545622Y198740D01*
X545312Y198587D01*
X545053Y198357D01*
X544950Y198088D01*
X545053Y197782D01*
X545363Y197513D01*
X545828Y197360D01*
X546345Y197322D01*
X547017Y197398D01*
X547378Y197513D01*
X547740Y197705D01*
X547998Y197973D01*
X548050Y198242D01*
X547947Y198510D01*
X547688Y198702D01*
G01X545415Y200307D02*
X545157Y200537D01*
X545002Y200805D01*
X544950Y201150D01*
X545053Y201495D01*
X545260Y201763D01*
X545622Y201955D01*
X546035Y201993D01*
X546448Y201917D01*
X546707Y201725D01*
X546913Y201457D01*
X546965Y201188D01*
X546913Y200920D01*
X546707Y200575D01*
X548050Y200690D01*
Y201725D01*
G01X544917Y221450D02*
Y224550D01*
X543958D01*
X543652Y224395D01*
X543460Y224188D01*
X543383Y223775D01*
X543460Y223362D01*
X543690Y223103D01*
X543958Y222948D01*
X544917D01*
G01X543958D02*
X543383Y221450D01*
G01X541778Y224033D02*
X541548Y224343D01*
X541280Y224498D01*
X540973Y224550D01*
X540590Y224447D01*
X540322Y224188D01*
X540245Y223878D01*
X540283Y223568D01*
X540437Y223310D01*
X541203Y222793D01*
X541548Y222432D01*
X541778Y221915D01*
X541855Y221450D01*
X540245D01*
G01X537490D02*
Y224550D01*
X538908Y222328D01*
X536992D01*
G01X535693Y222070D02*
X535463Y221708D01*
X535157Y221502D01*
X534812Y221450D01*
X534505Y221502D01*
X534198Y221760D01*
X534007Y222070D01*
X533968Y222380D01*
X534045Y222742D01*
X534313Y223000D01*
X534582Y223103D01*
X534927D01*
G01X534582D02*
X534352Y223258D01*
X534160Y223517D01*
X534083Y223827D01*
X534160Y224137D01*
X534352Y224395D01*
X534697Y224550D01*
X535042Y224498D01*
X535387Y224292D01*
G01X548950Y241583D02*
X552050D01*
Y242542D01*
X551895Y242848D01*
X551688Y243040D01*
X551275Y243117D01*
X550862Y243040D01*
X550603Y242810D01*
X550448Y242542D01*
Y241583D01*
G01Y242542D02*
X548950Y243117D01*
G01X551533Y244722D02*
X551843Y244952D01*
X551998Y245220D01*
X552050Y245527D01*
X551947Y245910D01*
X551688Y246178D01*
X551378Y246255D01*
X551068Y246217D01*
X550810Y246063D01*
X550293Y245297D01*
X549932Y244952D01*
X549415Y244722D01*
X548950Y244645D01*
Y246255D01*
G01Y249010D02*
X552050D01*
X549828Y247592D01*
Y249508D01*
G01X548950Y252110D02*
X552050D01*
X549828Y250692D01*
Y252608D01*
G01X544950Y241583D02*
X548050D01*
Y242542D01*
X547895Y242848D01*
X547688Y243040D01*
X547275Y243117D01*
X546862Y243040D01*
X546603Y242810D01*
X546448Y242542D01*
Y241583D01*
G01Y242542D02*
X544950Y243117D01*
G01X547533Y244722D02*
X547843Y244952D01*
X547998Y245220D01*
X548050Y245527D01*
X547947Y245910D01*
X547688Y246178D01*
X547378Y246255D01*
X547068Y246217D01*
X546810Y246063D01*
X546293Y245297D01*
X545932Y244952D01*
X545415Y244722D01*
X544950Y244645D01*
Y246255D01*
G01Y249010D02*
X548050D01*
X545828Y247592D01*
Y249508D01*
G01X544950Y251573D02*
X545622Y251650D01*
X546190Y251765D01*
X546707Y251918D01*
X547275Y252110D01*
X548050Y252417D01*
Y250883D01*
G01X538950Y257083D02*
X542050D01*
Y258042D01*
X541895Y258348D01*
X541688Y258540D01*
X541275Y258617D01*
X540862Y258540D01*
X540603Y258310D01*
X540448Y258042D01*
Y257083D01*
G01Y258042D02*
X538950Y258617D01*
G01Y261410D02*
X542050D01*
X539828Y259992D01*
Y261908D01*
G01X542050Y264050D02*
X541947Y263743D01*
X541688Y263513D01*
X541378Y263360D01*
X540965Y263245D01*
X540500Y263207D01*
X540035Y263245D01*
X539622Y263360D01*
X539312Y263513D01*
X539053Y263743D01*
X538950Y264050D01*
X539053Y264357D01*
X539312Y264587D01*
X539622Y264740D01*
X540035Y264855D01*
X540500Y264893D01*
X540965Y264855D01*
X541378Y264740D01*
X541688Y264587D01*
X541947Y264357D01*
X542050Y264050D01*
G01X541533Y266422D02*
X541843Y266652D01*
X541998Y266920D01*
X542050Y267227D01*
X541947Y267610D01*
X541688Y267878D01*
X541378Y267955D01*
X541068Y267917D01*
X540810Y267763D01*
X540293Y266997D01*
X539932Y266652D01*
X539415Y266422D01*
X538950Y266345D01*
Y267955D01*
G01X542367Y286450D02*
Y289550D01*
X541408D01*
X541102Y289395D01*
X540910Y289188D01*
X540833Y288775D01*
X540910Y288362D01*
X541140Y288103D01*
X541408Y287948D01*
X542367D01*
G01X541408D02*
X540833Y286450D01*
G01X538040D02*
Y289550D01*
X539458Y287328D01*
X537542D01*
G01X536243Y287070D02*
X536013Y286708D01*
X535707Y286502D01*
X535362Y286450D01*
X535055Y286502D01*
X534748Y286760D01*
X534557Y287070D01*
X534518Y287380D01*
X534595Y287742D01*
X534863Y288000D01*
X535132Y288103D01*
X535477D01*
G01X535132D02*
X534902Y288258D01*
X534710Y288517D01*
X534633Y288827D01*
X534710Y289137D01*
X534902Y289395D01*
X535247Y289550D01*
X535592Y289498D01*
X535937Y289292D01*
G01X559417Y294950D02*
Y298050D01*
X558458D01*
X558152Y297895D01*
X557960Y297688D01*
X557883Y297275D01*
X557960Y296862D01*
X558190Y296603D01*
X558458Y296448D01*
X559417D01*
G01X558458D02*
X557883Y294950D01*
G01X555550D02*
Y298050D01*
X556010Y297430D01*
G01Y294950D02*
X555090D01*
G01X553293Y295570D02*
X553063Y295208D01*
X552757Y295002D01*
X552412Y294950D01*
X552105Y295002D01*
X551798Y295260D01*
X551607Y295570D01*
X551568Y295880D01*
X551645Y296242D01*
X551913Y296500D01*
X552182Y296603D01*
X552527D01*
G01X552182D02*
X551952Y296758D01*
X551760Y297017D01*
X551683Y297327D01*
X551760Y297637D01*
X551952Y297895D01*
X552297Y298050D01*
X552642Y297998D01*
X552987Y297792D01*
G01X550078Y296242D02*
X549810Y296603D01*
X549580Y296810D01*
X549273Y296913D01*
X549005Y296810D01*
X548813Y296603D01*
X548660Y296293D01*
X548622Y295932D01*
X548660Y295622D01*
X548813Y295312D01*
X549043Y295053D01*
X549312Y294950D01*
X549618Y295053D01*
X549887Y295363D01*
X550040Y295828D01*
X550078Y296345D01*
X550002Y297017D01*
X549887Y297378D01*
X549695Y297740D01*
X549427Y297998D01*
X549158Y298050D01*
X548890Y297947D01*
X548698Y297688D01*
G01X539450Y305583D02*
X542550D01*
Y306542D01*
X542395Y306848D01*
X542188Y307040D01*
X541775Y307117D01*
X541362Y307040D01*
X541103Y306810D01*
X540948Y306542D01*
Y305583D01*
G01Y306542D02*
X539450Y307117D01*
G01Y309910D02*
X542550D01*
X540328Y308492D01*
Y310408D01*
G01X542550Y312550D02*
X542447Y312243D01*
X542188Y312013D01*
X541878Y311860D01*
X541465Y311745D01*
X541000Y311707D01*
X540535Y311745D01*
X540122Y311860D01*
X539812Y312013D01*
X539553Y312243D01*
X539450Y312550D01*
X539553Y312857D01*
X539812Y313087D01*
X540122Y313240D01*
X540535Y313355D01*
X541000Y313393D01*
X541465Y313355D01*
X541878Y313240D01*
X542188Y313087D01*
X542447Y312857D01*
X542550Y312550D01*
G01X539915Y314807D02*
X539657Y315037D01*
X539502Y315305D01*
X539450Y315650D01*
X539553Y315995D01*
X539760Y316263D01*
X540122Y316455D01*
X540535Y316493D01*
X540948Y316417D01*
X541207Y316225D01*
X541413Y315957D01*
X541465Y315688D01*
X541413Y315420D01*
X541207Y315075D01*
X542550Y315190D01*
Y316225D01*
G01X557917Y309450D02*
Y312550D01*
X556958D01*
X556652Y312395D01*
X556460Y312188D01*
X556383Y311775D01*
X556460Y311362D01*
X556690Y311103D01*
X556958Y310948D01*
X557917D01*
G01X556958D02*
X556383Y309450D01*
G01X554050D02*
Y312550D01*
X554510Y311930D01*
G01Y309450D02*
X553590D01*
G01X551793Y310070D02*
X551563Y309708D01*
X551257Y309502D01*
X550912Y309450D01*
X550605Y309502D01*
X550298Y309760D01*
X550107Y310070D01*
X550068Y310380D01*
X550145Y310742D01*
X550413Y311000D01*
X550682Y311103D01*
X551027D01*
G01X550682D02*
X550452Y311258D01*
X550260Y311517D01*
X550183Y311827D01*
X550260Y312137D01*
X550452Y312395D01*
X550797Y312550D01*
X551142Y312498D01*
X551487Y312292D01*
G01X547927Y309450D02*
X547850Y310122D01*
X547735Y310690D01*
X547582Y311207D01*
X547390Y311775D01*
X547083Y312550D01*
X548617D01*
G01X557867Y313450D02*
Y316550D01*
X556908D01*
X556602Y316395D01*
X556410Y316188D01*
X556333Y315775D01*
X556410Y315362D01*
X556640Y315103D01*
X556908Y314948D01*
X557867D01*
G01X556908D02*
X556333Y313450D01*
G01X553540D02*
Y316550D01*
X554958Y314328D01*
X553042D01*
G01X550900Y313450D02*
Y316550D01*
X551360Y315930D01*
G01Y313450D02*
X550440D01*
G01X555307Y356292D02*
X555537Y356447D01*
X555805Y356550D01*
X556112D01*
X556457Y356395D01*
X556725Y356137D01*
X556917Y355827D01*
X557070Y355310D01*
X557108Y354845D01*
X557032Y354380D01*
X556917Y354070D01*
X556687Y353760D01*
X556418Y353553D01*
X556150Y353450D01*
X555882D01*
X555613Y353553D01*
X555383Y353708D01*
X555192Y353915D01*
G01X553778Y356033D02*
X553548Y356343D01*
X553280Y356498D01*
X552973Y356550D01*
X552590Y356447D01*
X552322Y356188D01*
X552245Y355878D01*
X552283Y355568D01*
X552437Y355310D01*
X553203Y354793D01*
X553548Y354432D01*
X553778Y353915D01*
X553855Y353450D01*
X552245D01*
G01X550602Y353812D02*
X550333Y353553D01*
X550027Y353450D01*
X549720Y353553D01*
X549452Y353863D01*
X549260Y354328D01*
X549183Y354793D01*
Y355362D01*
X549260Y355827D01*
X549452Y356240D01*
X549682Y356447D01*
X549950Y356550D01*
X550257Y356447D01*
X550487Y356240D01*
X550640Y355930D01*
X550717Y355517D01*
X550640Y355155D01*
X550448Y354793D01*
X550218Y354587D01*
X549950Y354535D01*
X549643Y354638D01*
X549413Y354897D01*
X549183Y355362D01*
G01X547502Y353812D02*
X547233Y353553D01*
X546927Y353450D01*
X546620Y353553D01*
X546352Y353863D01*
X546160Y354328D01*
X546083Y354793D01*
Y355362D01*
X546160Y355827D01*
X546352Y356240D01*
X546582Y356447D01*
X546850Y356550D01*
X547157Y356447D01*
X547387Y356240D01*
X547540Y355930D01*
X547617Y355517D01*
X547540Y355155D01*
X547348Y354793D01*
X547118Y354587D01*
X546850Y354535D01*
X546543Y354638D01*
X546313Y354897D01*
X546083Y355362D01*
G01X555807Y352292D02*
X556037Y352447D01*
X556305Y352550D01*
X556612D01*
X556957Y352395D01*
X557225Y352137D01*
X557417Y351827D01*
X557570Y351310D01*
X557608Y350845D01*
X557532Y350380D01*
X557417Y350070D01*
X557187Y349760D01*
X556918Y349553D01*
X556650Y349450D01*
X556382D01*
X556113Y349553D01*
X555883Y349708D01*
X555692Y349915D01*
G01X554393Y350070D02*
X554163Y349708D01*
X553857Y349502D01*
X553512Y349450D01*
X553205Y349502D01*
X552898Y349760D01*
X552707Y350070D01*
X552668Y350380D01*
X552745Y350742D01*
X553013Y351000D01*
X553282Y351103D01*
X553627D01*
G01X553282D02*
X553052Y351258D01*
X552860Y351517D01*
X552783Y351827D01*
X552860Y352137D01*
X553052Y352395D01*
X553397Y352550D01*
X553742Y352498D01*
X554087Y352292D01*
G01X550450Y352550D02*
X550757Y352447D01*
X550987Y352188D01*
X551140Y351878D01*
X551255Y351465D01*
X551293Y351000D01*
X551255Y350535D01*
X551140Y350122D01*
X550987Y349812D01*
X550757Y349553D01*
X550450Y349450D01*
X550143Y349553D01*
X549913Y349812D01*
X549760Y350122D01*
X549645Y350535D01*
X549607Y351000D01*
X549645Y351465D01*
X549760Y351878D01*
X549913Y352188D01*
X550143Y352447D01*
X550450Y352550D01*
G01X548193Y350070D02*
X547963Y349708D01*
X547657Y349502D01*
X547312Y349450D01*
X547005Y349502D01*
X546698Y349760D01*
X546507Y350070D01*
X546468Y350380D01*
X546545Y350742D01*
X546813Y351000D01*
X547082Y351103D01*
X547427D01*
G01X547082D02*
X546852Y351258D01*
X546660Y351517D01*
X546583Y351827D01*
X546660Y352137D01*
X546852Y352395D01*
X547197Y352550D01*
X547542Y352498D01*
X547887Y352292D01*
G01X554807Y365292D02*
X555037Y365447D01*
X555305Y365550D01*
X555612D01*
X555957Y365395D01*
X556225Y365137D01*
X556417Y364827D01*
X556570Y364310D01*
X556608Y363845D01*
X556532Y363380D01*
X556417Y363070D01*
X556187Y362760D01*
X555918Y362553D01*
X555650Y362450D01*
X555382D01*
X555113Y362553D01*
X554883Y362708D01*
X554692Y362915D01*
G01X553393Y363070D02*
X553163Y362708D01*
X552857Y362502D01*
X552512Y362450D01*
X552205Y362502D01*
X551898Y362760D01*
X551707Y363070D01*
X551668Y363380D01*
X551745Y363742D01*
X552013Y364000D01*
X552282Y364103D01*
X552627D01*
G01X552282D02*
X552052Y364258D01*
X551860Y364517D01*
X551783Y364827D01*
X551860Y365137D01*
X552052Y365395D01*
X552397Y365550D01*
X552742Y365498D01*
X553087Y365292D01*
G01X549450Y365550D02*
X549757Y365447D01*
X549987Y365188D01*
X550140Y364878D01*
X550255Y364465D01*
X550293Y364000D01*
X550255Y363535D01*
X550140Y363122D01*
X549987Y362812D01*
X549757Y362553D01*
X549450Y362450D01*
X549143Y362553D01*
X548913Y362812D01*
X548760Y363122D01*
X548645Y363535D01*
X548607Y364000D01*
X548645Y364465D01*
X548760Y364878D01*
X548913Y365188D01*
X549143Y365447D01*
X549450Y365550D01*
G01X546350Y362450D02*
Y365550D01*
X546810Y364930D01*
G01Y362450D02*
X545890D01*
G01X555307Y360792D02*
X555537Y360947D01*
X555805Y361050D01*
X556112D01*
X556457Y360895D01*
X556725Y360637D01*
X556917Y360327D01*
X557070Y359810D01*
X557108Y359345D01*
X557032Y358880D01*
X556917Y358570D01*
X556687Y358260D01*
X556418Y358053D01*
X556150Y357950D01*
X555882D01*
X555613Y358053D01*
X555383Y358208D01*
X555192Y358415D01*
G01X553778Y360533D02*
X553548Y360843D01*
X553280Y360998D01*
X552973Y361050D01*
X552590Y360947D01*
X552322Y360688D01*
X552245Y360378D01*
X552283Y360068D01*
X552437Y359810D01*
X553203Y359293D01*
X553548Y358932D01*
X553778Y358415D01*
X553855Y357950D01*
X552245D01*
G01X550602Y358312D02*
X550333Y358053D01*
X550027Y357950D01*
X549720Y358053D01*
X549452Y358363D01*
X549260Y358828D01*
X549183Y359293D01*
Y359862D01*
X549260Y360327D01*
X549452Y360740D01*
X549682Y360947D01*
X549950Y361050D01*
X550257Y360947D01*
X550487Y360740D01*
X550640Y360430D01*
X550717Y360017D01*
X550640Y359655D01*
X550448Y359293D01*
X550218Y359087D01*
X549950Y359035D01*
X549643Y359138D01*
X549413Y359397D01*
X549183Y359862D01*
G01X546927Y357950D02*
X546850Y358622D01*
X546735Y359190D01*
X546582Y359707D01*
X546390Y360275D01*
X546083Y361050D01*
X547617D01*
G01X556917Y390950D02*
Y394050D01*
X555958D01*
X555652Y393895D01*
X555460Y393688D01*
X555383Y393275D01*
X555460Y392862D01*
X555690Y392603D01*
X555958Y392448D01*
X556917D01*
G01X555958D02*
X555383Y390950D01*
G01X553050D02*
Y394050D01*
X553510Y393430D01*
G01Y390950D02*
X552590D01*
G01X550793Y391570D02*
X550563Y391208D01*
X550257Y391002D01*
X549912Y390950D01*
X549605Y391002D01*
X549298Y391260D01*
X549107Y391570D01*
X549068Y391880D01*
X549145Y392242D01*
X549413Y392500D01*
X549682Y392603D01*
X550027D01*
G01X549682D02*
X549452Y392758D01*
X549260Y393017D01*
X549183Y393327D01*
X549260Y393637D01*
X549452Y393895D01*
X549797Y394050D01*
X550142Y393998D01*
X550487Y393792D01*
G01X547502Y391312D02*
X547233Y391053D01*
X546927Y390950D01*
X546620Y391053D01*
X546352Y391363D01*
X546160Y391828D01*
X546083Y392293D01*
Y392862D01*
X546160Y393327D01*
X546352Y393740D01*
X546582Y393947D01*
X546850Y394050D01*
X547157Y393947D01*
X547387Y393740D01*
X547540Y393430D01*
X547617Y393017D01*
X547540Y392655D01*
X547348Y392293D01*
X547118Y392087D01*
X546850Y392035D01*
X546543Y392138D01*
X546313Y392397D01*
X546083Y392862D01*
G01X534450Y382083D02*
X537550D01*
Y383042D01*
X537395Y383348D01*
X537188Y383540D01*
X536775Y383617D01*
X536362Y383540D01*
X536103Y383310D01*
X535948Y383042D01*
Y382083D01*
G01Y383042D02*
X534450Y383617D01*
G01X537033Y385222D02*
X537343Y385452D01*
X537498Y385720D01*
X537550Y386027D01*
X537447Y386410D01*
X537188Y386678D01*
X536878Y386755D01*
X536568Y386717D01*
X536310Y386563D01*
X535793Y385797D01*
X535432Y385452D01*
X534915Y385222D01*
X534450Y385145D01*
Y386755D01*
G01X537550Y389050D02*
X537447Y388743D01*
X537188Y388513D01*
X536878Y388360D01*
X536465Y388245D01*
X536000Y388207D01*
X535535Y388245D01*
X535122Y388360D01*
X534812Y388513D01*
X534553Y388743D01*
X534450Y389050D01*
X534553Y389357D01*
X534812Y389587D01*
X535122Y389740D01*
X535535Y389855D01*
X536000Y389893D01*
X536465Y389855D01*
X536878Y389740D01*
X537188Y389587D01*
X537447Y389357D01*
X537550Y389050D01*
G01X534450Y392150D02*
X534502Y392418D01*
X534657Y392725D01*
X534915Y392917D01*
X535277Y392993D01*
X535638Y392917D01*
X535948Y392687D01*
X536103Y392342D01*
Y391958D01*
X536207Y391728D01*
X536465Y391537D01*
X536827Y391460D01*
X537188Y391575D01*
X537447Y391843D01*
X537550Y392150D01*
X537447Y392457D01*
X537188Y392725D01*
X536827Y392840D01*
X536465Y392763D01*
X536207Y392572D01*
X536103Y392342D01*
Y391958D01*
X535948Y391613D01*
X535638Y391383D01*
X535277Y391307D01*
X534915Y391383D01*
X534657Y391575D01*
X534502Y391882D01*
X534450Y392150D01*
G01X537157Y379792D02*
X537387Y379947D01*
X537655Y380050D01*
X537962D01*
X538307Y379895D01*
X538575Y379637D01*
X538767Y379327D01*
X538920Y378810D01*
X538958Y378345D01*
X538882Y377880D01*
X538767Y377570D01*
X538537Y377260D01*
X538268Y377053D01*
X538000Y376950D01*
X537732D01*
X537463Y377053D01*
X537233Y377208D01*
X537042Y377415D01*
G01X547917Y403450D02*
Y406550D01*
X546958D01*
X546652Y406395D01*
X546460Y406188D01*
X546383Y405775D01*
X546460Y405362D01*
X546690Y405103D01*
X546958Y404948D01*
X547917D01*
G01X546958D02*
X546383Y403450D01*
G01X544050D02*
Y406550D01*
X544510Y405930D01*
G01Y403450D02*
X543590D01*
G01X541793Y404070D02*
X541563Y403708D01*
X541257Y403502D01*
X540912Y403450D01*
X540605Y403502D01*
X540298Y403760D01*
X540107Y404070D01*
X540068Y404380D01*
X540145Y404742D01*
X540413Y405000D01*
X540682Y405103D01*
X541027D01*
G01X540682D02*
X540452Y405258D01*
X540260Y405517D01*
X540183Y405827D01*
X540260Y406137D01*
X540452Y406395D01*
X540797Y406550D01*
X541142Y406498D01*
X541487Y406292D01*
G01X537850Y403450D02*
X537582Y403502D01*
X537275Y403657D01*
X537083Y403915D01*
X537007Y404277D01*
X537083Y404638D01*
X537313Y404948D01*
X537658Y405103D01*
X538042D01*
X538272Y405207D01*
X538463Y405465D01*
X538540Y405827D01*
X538425Y406188D01*
X538157Y406447D01*
X537850Y406550D01*
X537543Y406447D01*
X537275Y406188D01*
X537160Y405827D01*
X537237Y405465D01*
X537428Y405207D01*
X537658Y405103D01*
X538042D01*
X538387Y404948D01*
X538617Y404638D01*
X538693Y404277D01*
X538617Y403915D01*
X538425Y403657D01*
X538118Y403502D01*
X537850Y403450D01*
G01X556917Y394950D02*
Y398050D01*
X555958D01*
X555652Y397895D01*
X555460Y397688D01*
X555383Y397275D01*
X555460Y396862D01*
X555690Y396603D01*
X555958Y396448D01*
X556917D01*
G01X555958D02*
X555383Y394950D01*
G01X553050D02*
Y398050D01*
X553510Y397430D01*
G01Y394950D02*
X552590D01*
G01X549950Y398050D02*
X550257Y397947D01*
X550487Y397688D01*
X550640Y397378D01*
X550755Y396965D01*
X550793Y396500D01*
X550755Y396035D01*
X550640Y395622D01*
X550487Y395312D01*
X550257Y395053D01*
X549950Y394950D01*
X549643Y395053D01*
X549413Y395312D01*
X549260Y395622D01*
X549145Y396035D01*
X549107Y396500D01*
X549145Y396965D01*
X549260Y397378D01*
X549413Y397688D01*
X549643Y397947D01*
X549950Y398050D01*
G01X546850Y394950D02*
X546582Y395002D01*
X546275Y395157D01*
X546083Y395415D01*
X546007Y395777D01*
X546083Y396138D01*
X546313Y396448D01*
X546658Y396603D01*
X547042D01*
X547272Y396707D01*
X547463Y396965D01*
X547540Y397327D01*
X547425Y397688D01*
X547157Y397947D01*
X546850Y398050D01*
X546543Y397947D01*
X546275Y397688D01*
X546160Y397327D01*
X546237Y396965D01*
X546428Y396707D01*
X546658Y396603D01*
X547042D01*
X547387Y396448D01*
X547617Y396138D01*
X547693Y395777D01*
X547617Y395415D01*
X547425Y395157D01*
X547118Y395002D01*
X546850Y394950D01*
G01X547917Y399450D02*
Y402550D01*
X546958D01*
X546652Y402395D01*
X546460Y402188D01*
X546383Y401775D01*
X546460Y401362D01*
X546690Y401103D01*
X546958Y400948D01*
X547917D01*
G01X546958D02*
X546383Y399450D01*
G01X544778Y402033D02*
X544548Y402343D01*
X544280Y402498D01*
X543973Y402550D01*
X543590Y402447D01*
X543322Y402188D01*
X543245Y401878D01*
X543283Y401568D01*
X543437Y401310D01*
X544203Y400793D01*
X544548Y400432D01*
X544778Y399915D01*
X544855Y399450D01*
X543245D01*
G01X541793Y399915D02*
X541563Y399657D01*
X541295Y399502D01*
X540950Y399450D01*
X540605Y399553D01*
X540337Y399760D01*
X540145Y400122D01*
X540107Y400535D01*
X540183Y400948D01*
X540375Y401207D01*
X540643Y401413D01*
X540912Y401465D01*
X541180Y401413D01*
X541525Y401207D01*
X541410Y402550D01*
X540375D01*
G01X537927Y399450D02*
X537850Y400122D01*
X537735Y400690D01*
X537582Y401207D01*
X537390Y401775D01*
X537083Y402550D01*
X538617D01*
G01X553450Y92583D02*
X556550D01*
Y93542D01*
X556395Y93848D01*
X556188Y94040D01*
X555775Y94117D01*
X555362Y94040D01*
X555103Y93810D01*
X554948Y93542D01*
Y92583D01*
G01Y93542D02*
X553450Y94117D01*
G01X556033Y95722D02*
X556343Y95952D01*
X556498Y96220D01*
X556550Y96527D01*
X556447Y96910D01*
X556188Y97178D01*
X555878Y97255D01*
X555568Y97217D01*
X555310Y97063D01*
X554793Y96297D01*
X554432Y95952D01*
X553915Y95722D01*
X553450Y95645D01*
Y97255D01*
G01X554070Y98707D02*
X553708Y98937D01*
X553502Y99243D01*
X553450Y99588D01*
X553502Y99895D01*
X553760Y100202D01*
X554070Y100393D01*
X554380Y100432D01*
X554742Y100355D01*
X555000Y100087D01*
X555103Y99818D01*
Y99473D01*
G01Y99818D02*
X555258Y100048D01*
X555517Y100240D01*
X555827Y100317D01*
X556137Y100240D01*
X556395Y100048D01*
X556550Y99703D01*
X556498Y99358D01*
X556292Y99013D01*
G01X556033Y101922D02*
X556343Y102152D01*
X556498Y102420D01*
X556550Y102727D01*
X556447Y103110D01*
X556188Y103378D01*
X555878Y103455D01*
X555568Y103417D01*
X555310Y103263D01*
X554793Y102497D01*
X554432Y102152D01*
X553915Y101922D01*
X553450Y101845D01*
Y103455D01*
G01Y80083D02*
X556550D01*
Y81042D01*
X556395Y81348D01*
X556188Y81540D01*
X555775Y81617D01*
X555362Y81540D01*
X555103Y81310D01*
X554948Y81042D01*
Y80083D01*
G01Y81042D02*
X553450Y81617D01*
G01X556033Y83222D02*
X556343Y83452D01*
X556498Y83720D01*
X556550Y84027D01*
X556447Y84410D01*
X556188Y84678D01*
X555878Y84755D01*
X555568Y84717D01*
X555310Y84563D01*
X554793Y83797D01*
X554432Y83452D01*
X553915Y83222D01*
X553450Y83145D01*
Y84755D01*
G01X556033Y86322D02*
X556343Y86552D01*
X556498Y86820D01*
X556550Y87127D01*
X556447Y87510D01*
X556188Y87778D01*
X555878Y87855D01*
X555568Y87817D01*
X555310Y87663D01*
X554793Y86897D01*
X554432Y86552D01*
X553915Y86322D01*
X553450Y86245D01*
Y87855D01*
G01X553812Y89498D02*
X553553Y89767D01*
X553450Y90073D01*
X553553Y90380D01*
X553863Y90648D01*
X554328Y90840D01*
X554793Y90917D01*
X555362D01*
X555827Y90840D01*
X556240Y90648D01*
X556447Y90418D01*
X556550Y90150D01*
X556447Y89843D01*
X556240Y89613D01*
X555930Y89460D01*
X555517Y89383D01*
X555155Y89460D01*
X554793Y89652D01*
X554587Y89882D01*
X554535Y90150D01*
X554638Y90457D01*
X554897Y90687D01*
X555362Y90917D01*
G01X563807Y193292D02*
X564037Y193447D01*
X564305Y193550D01*
X564612D01*
X564957Y193395D01*
X565225Y193137D01*
X565417Y192827D01*
X565570Y192310D01*
X565608Y191845D01*
X565532Y191380D01*
X565417Y191070D01*
X565187Y190760D01*
X564918Y190553D01*
X564650Y190450D01*
X564382D01*
X564113Y190553D01*
X563883Y190708D01*
X563692Y190915D01*
G01X562278Y193033D02*
X562048Y193343D01*
X561780Y193498D01*
X561473Y193550D01*
X561090Y193447D01*
X560822Y193188D01*
X560745Y192878D01*
X560783Y192568D01*
X560937Y192310D01*
X561703Y191793D01*
X562048Y191432D01*
X562278Y190915D01*
X562355Y190450D01*
X560745D01*
G01X559178Y191742D02*
X558910Y192103D01*
X558680Y192310D01*
X558373Y192413D01*
X558105Y192310D01*
X557913Y192103D01*
X557760Y191793D01*
X557722Y191432D01*
X557760Y191122D01*
X557913Y190812D01*
X558143Y190553D01*
X558412Y190450D01*
X558718Y190553D01*
X558987Y190863D01*
X559140Y191328D01*
X559178Y191845D01*
X559102Y192517D01*
X558987Y192878D01*
X558795Y193240D01*
X558527Y193498D01*
X558258Y193550D01*
X557990Y193447D01*
X557798Y193188D01*
G01X556078Y191742D02*
X555810Y192103D01*
X555580Y192310D01*
X555273Y192413D01*
X555005Y192310D01*
X554813Y192103D01*
X554660Y191793D01*
X554622Y191432D01*
X554660Y191122D01*
X554813Y190812D01*
X555043Y190553D01*
X555312Y190450D01*
X555618Y190553D01*
X555887Y190863D01*
X556040Y191328D01*
X556078Y191845D01*
X556002Y192517D01*
X555887Y192878D01*
X555695Y193240D01*
X555427Y193498D01*
X555158Y193550D01*
X554890Y193447D01*
X554698Y193188D01*
G01X578417Y190450D02*
Y193550D01*
X577458D01*
X577152Y193395D01*
X576960Y193188D01*
X576883Y192775D01*
X576960Y192362D01*
X577190Y192103D01*
X577458Y191948D01*
X578417D01*
G01X577458D02*
X576883Y190450D01*
G01X575278Y193033D02*
X575048Y193343D01*
X574780Y193498D01*
X574473Y193550D01*
X574090Y193447D01*
X573822Y193188D01*
X573745Y192878D01*
X573783Y192568D01*
X573937Y192310D01*
X574703Y191793D01*
X575048Y191432D01*
X575278Y190915D01*
X575355Y190450D01*
X573745D01*
G01X572293Y190915D02*
X572063Y190657D01*
X571795Y190502D01*
X571450Y190450D01*
X571105Y190553D01*
X570837Y190760D01*
X570645Y191122D01*
X570607Y191535D01*
X570683Y191948D01*
X570875Y192207D01*
X571143Y192413D01*
X571412Y192465D01*
X571680Y192413D01*
X572025Y192207D01*
X571910Y193550D01*
X570875D01*
G01X569193Y191070D02*
X568963Y190708D01*
X568657Y190502D01*
X568312Y190450D01*
X568005Y190502D01*
X567698Y190760D01*
X567507Y191070D01*
X567468Y191380D01*
X567545Y191742D01*
X567813Y192000D01*
X568082Y192103D01*
X568427D01*
G01X568082D02*
X567852Y192258D01*
X567660Y192517D01*
X567583Y192827D01*
X567660Y193137D01*
X567852Y193395D01*
X568197Y193550D01*
X568542Y193498D01*
X568887Y193292D01*
G01X553950Y211583D02*
X557050D01*
Y212542D01*
X556895Y212848D01*
X556688Y213040D01*
X556275Y213117D01*
X555862Y213040D01*
X555603Y212810D01*
X555448Y212542D01*
Y211583D01*
G01Y212542D02*
X553950Y213117D01*
G01X556533Y214722D02*
X556843Y214952D01*
X556998Y215220D01*
X557050Y215527D01*
X556947Y215910D01*
X556688Y216178D01*
X556378Y216255D01*
X556068Y216217D01*
X555810Y216063D01*
X555293Y215297D01*
X554932Y214952D01*
X554415Y214722D01*
X553950Y214645D01*
Y216255D01*
G01X554415Y217707D02*
X554157Y217937D01*
X554002Y218205D01*
X553950Y218550D01*
X554053Y218895D01*
X554260Y219163D01*
X554622Y219355D01*
X555035Y219393D01*
X555448Y219317D01*
X555707Y219125D01*
X555913Y218857D01*
X555965Y218588D01*
X555913Y218320D01*
X555707Y217975D01*
X557050Y218090D01*
Y219125D01*
G01Y221650D02*
X556947Y221343D01*
X556688Y221113D01*
X556378Y220960D01*
X555965Y220845D01*
X555500Y220807D01*
X555035Y220845D01*
X554622Y220960D01*
X554312Y221113D01*
X554053Y221343D01*
X553950Y221650D01*
X554053Y221957D01*
X554312Y222187D01*
X554622Y222340D01*
X555035Y222455D01*
X555500Y222493D01*
X555965Y222455D01*
X556378Y222340D01*
X556688Y222187D01*
X556947Y221957D01*
X557050Y221650D01*
G01X568905Y208863D02*
X568598Y208605D01*
X568253Y208450D01*
X567947D01*
X567640Y208605D01*
X567410Y208863D01*
X567295Y209225D01*
X567372Y209587D01*
X567563Y209897D01*
X567908Y210103D01*
X568368Y210207D01*
X568637Y210413D01*
X568752Y210775D01*
X568675Y211137D01*
X568483Y211395D01*
X568215Y211550D01*
X567947D01*
X567678Y211447D01*
X567448Y211188D01*
G01X565767Y208450D02*
Y211550D01*
X564847D01*
X564540Y211395D01*
X564310Y211033D01*
X564233Y210620D01*
X564310Y210207D01*
X564502Y209897D01*
X564847Y209742D01*
X565767D01*
G01X562743Y209070D02*
X562513Y208708D01*
X562207Y208502D01*
X561862Y208450D01*
X561555Y208502D01*
X561248Y208760D01*
X561057Y209070D01*
X561018Y209380D01*
X561095Y209742D01*
X561363Y210000D01*
X561632Y210103D01*
X561977D01*
G01X561632D02*
X561402Y210258D01*
X561210Y210517D01*
X561133Y210827D01*
X561210Y211137D01*
X561402Y211395D01*
X561747Y211550D01*
X562092Y211498D01*
X562437Y211292D01*
G01X566292Y244193D02*
X566447Y243963D01*
X566550Y243695D01*
Y243388D01*
X566395Y243043D01*
X566137Y242775D01*
X565827Y242583D01*
X565310Y242430D01*
X564845Y242392D01*
X564380Y242468D01*
X564070Y242583D01*
X563760Y242813D01*
X563553Y243082D01*
X563450Y243350D01*
Y243618D01*
X563553Y243887D01*
X563708Y244117D01*
X563915Y244308D01*
G01X566033Y245722D02*
X566343Y245952D01*
X566498Y246220D01*
X566550Y246527D01*
X566447Y246910D01*
X566188Y247178D01*
X565878Y247255D01*
X565568Y247217D01*
X565310Y247063D01*
X564793Y246297D01*
X564432Y245952D01*
X563915Y245722D01*
X563450Y245645D01*
Y247255D01*
G01X564742Y248822D02*
X565103Y249090D01*
X565310Y249320D01*
X565413Y249627D01*
X565310Y249895D01*
X565103Y250087D01*
X564793Y250240D01*
X564432Y250278D01*
X564122Y250240D01*
X563812Y250087D01*
X563553Y249857D01*
X563450Y249588D01*
X563553Y249282D01*
X563863Y249013D01*
X564328Y248860D01*
X564845Y248822D01*
X565517Y248898D01*
X565878Y249013D01*
X566240Y249205D01*
X566498Y249473D01*
X566550Y249742D01*
X566447Y250010D01*
X566188Y250202D01*
G01X564070Y251807D02*
X563708Y252037D01*
X563502Y252343D01*
X563450Y252688D01*
X563502Y252995D01*
X563760Y253302D01*
X564070Y253493D01*
X564380Y253532D01*
X564742Y253455D01*
X565000Y253187D01*
X565103Y252918D01*
Y252573D01*
G01Y252918D02*
X565258Y253148D01*
X565517Y253340D01*
X565827Y253417D01*
X566137Y253340D01*
X566395Y253148D01*
X566550Y252803D01*
X566498Y252458D01*
X566292Y252113D01*
G01X557950Y241583D02*
X561050D01*
Y242542D01*
X560895Y242848D01*
X560688Y243040D01*
X560275Y243117D01*
X559862Y243040D01*
X559603Y242810D01*
X559448Y242542D01*
Y241583D01*
G01Y242542D02*
X557950Y243117D01*
G01X560533Y244722D02*
X560843Y244952D01*
X560998Y245220D01*
X561050Y245527D01*
X560947Y245910D01*
X560688Y246178D01*
X560378Y246255D01*
X560068Y246217D01*
X559810Y246063D01*
X559293Y245297D01*
X558932Y244952D01*
X558415Y244722D01*
X557950Y244645D01*
Y246255D01*
G01Y249010D02*
X561050D01*
X558828Y247592D01*
Y249508D01*
G01X558312Y250998D02*
X558053Y251267D01*
X557950Y251573D01*
X558053Y251880D01*
X558363Y252148D01*
X558828Y252340D01*
X559293Y252417D01*
X559862D01*
X560327Y252340D01*
X560740Y252148D01*
X560947Y251918D01*
X561050Y251650D01*
X560947Y251343D01*
X560740Y251113D01*
X560430Y250960D01*
X560017Y250883D01*
X559655Y250960D01*
X559293Y251152D01*
X559087Y251382D01*
X559035Y251650D01*
X559138Y251957D01*
X559397Y252187D01*
X559862Y252417D01*
G01X553450Y241583D02*
X556550D01*
Y242542D01*
X556395Y242848D01*
X556188Y243040D01*
X555775Y243117D01*
X555362Y243040D01*
X555103Y242810D01*
X554948Y242542D01*
Y241583D01*
G01Y242542D02*
X553450Y243117D01*
G01X556033Y244722D02*
X556343Y244952D01*
X556498Y245220D01*
X556550Y245527D01*
X556447Y245910D01*
X556188Y246178D01*
X555878Y246255D01*
X555568Y246217D01*
X555310Y246063D01*
X554793Y245297D01*
X554432Y244952D01*
X553915Y244722D01*
X553450Y244645D01*
Y246255D01*
G01Y249010D02*
X556550D01*
X554328Y247592D01*
Y249508D01*
G01X554742Y250922D02*
X555103Y251190D01*
X555310Y251420D01*
X555413Y251727D01*
X555310Y251995D01*
X555103Y252187D01*
X554793Y252340D01*
X554432Y252378D01*
X554122Y252340D01*
X553812Y252187D01*
X553553Y251957D01*
X553450Y251688D01*
X553553Y251382D01*
X553863Y251113D01*
X554328Y250960D01*
X554845Y250922D01*
X555517Y250998D01*
X555878Y251113D01*
X556240Y251305D01*
X556498Y251573D01*
X556550Y251842D01*
X556447Y252110D01*
X556188Y252302D01*
G01X567728Y258033D02*
X567498Y258343D01*
X567230Y258498D01*
X566923Y258550D01*
X566540Y258447D01*
X566272Y258188D01*
X566195Y257878D01*
X566233Y257568D01*
X566387Y257310D01*
X567153Y256793D01*
X567498Y256432D01*
X567728Y255915D01*
X567805Y255450D01*
X566195D01*
G01X557950Y263083D02*
X561050D01*
Y264042D01*
X560895Y264348D01*
X560688Y264540D01*
X560275Y264617D01*
X559862Y264540D01*
X559603Y264310D01*
X559448Y264042D01*
Y263083D01*
G01Y264042D02*
X557950Y264617D01*
G01Y266950D02*
X561050D01*
X560430Y266490D01*
G01X557950D02*
Y267410D01*
G01X558570Y269207D02*
X558208Y269437D01*
X558002Y269743D01*
X557950Y270088D01*
X558002Y270395D01*
X558260Y270702D01*
X558570Y270893D01*
X558880Y270932D01*
X559242Y270855D01*
X559500Y270587D01*
X559603Y270318D01*
Y269973D01*
G01Y270318D02*
X559758Y270548D01*
X560017Y270740D01*
X560327Y270817D01*
X560637Y270740D01*
X560895Y270548D01*
X561050Y270203D01*
X560998Y269858D01*
X560792Y269513D01*
G01X557950Y273610D02*
X561050D01*
X558828Y272192D01*
Y274108D01*
G01X557950Y254133D02*
X561050D01*
Y255092D01*
X560895Y255398D01*
X560688Y255590D01*
X560275Y255667D01*
X559862Y255590D01*
X559603Y255360D01*
X559448Y255092D01*
Y254133D01*
G01Y255092D02*
X557950Y255667D01*
G01X560533Y257272D02*
X560843Y257502D01*
X560998Y257770D01*
X561050Y258077D01*
X560947Y258460D01*
X560688Y258728D01*
X560378Y258805D01*
X560068Y258767D01*
X559810Y258613D01*
X559293Y257847D01*
X558932Y257502D01*
X558415Y257272D01*
X557950Y257195D01*
Y258805D01*
G01Y261100D02*
X558002Y261368D01*
X558157Y261675D01*
X558415Y261867D01*
X558777Y261943D01*
X559138Y261867D01*
X559448Y261637D01*
X559603Y261292D01*
Y260908D01*
X559707Y260678D01*
X559965Y260487D01*
X560327Y260410D01*
X560688Y260525D01*
X560947Y260793D01*
X561050Y261100D01*
X560947Y261407D01*
X560688Y261675D01*
X560327Y261790D01*
X559965Y261713D01*
X559707Y261522D01*
X559603Y261292D01*
Y260908D01*
X559448Y260563D01*
X559138Y260333D01*
X558777Y260257D01*
X558415Y260333D01*
X558157Y260525D01*
X558002Y260832D01*
X557950Y261100D01*
G01X566728Y286533D02*
X566498Y286843D01*
X566230Y286998D01*
X565923Y287050D01*
X565540Y286947D01*
X565272Y286688D01*
X565195Y286378D01*
X565233Y286068D01*
X565387Y285810D01*
X566153Y285293D01*
X566498Y284932D01*
X566728Y284415D01*
X566805Y283950D01*
X565195D01*
G01X573757Y281792D02*
X573987Y281947D01*
X574255Y282050D01*
X574562D01*
X574907Y281895D01*
X575175Y281637D01*
X575367Y281327D01*
X575520Y280810D01*
X575558Y280345D01*
X575482Y279880D01*
X575367Y279570D01*
X575137Y279260D01*
X574868Y279053D01*
X574600Y278950D01*
X574332D01*
X574063Y279053D01*
X573833Y279208D01*
X573642Y279415D01*
G01X572267Y278950D02*
Y282050D01*
X571308D01*
X571002Y281895D01*
X570810Y281688D01*
X570733Y281275D01*
X570810Y280862D01*
X571040Y280603D01*
X571308Y280448D01*
X572267D01*
G01X571308D02*
X570733Y278950D01*
G01X568477D02*
X568400Y279622D01*
X568285Y280190D01*
X568132Y280707D01*
X567940Y281275D01*
X567633Y282050D01*
X569167D01*
G01X563843Y274570D02*
X563613Y274208D01*
X563307Y274002D01*
X562962Y273950D01*
X562655Y274002D01*
X562348Y274260D01*
X562157Y274570D01*
X562118Y274880D01*
X562195Y275242D01*
X562463Y275500D01*
X562732Y275603D01*
X563077D01*
G01X562732D02*
X562502Y275758D01*
X562310Y276017D01*
X562233Y276327D01*
X562310Y276637D01*
X562502Y276895D01*
X562847Y277050D01*
X563192Y276998D01*
X563537Y276792D01*
G01X566343Y306570D02*
X566113Y306208D01*
X565807Y306002D01*
X565462Y305950D01*
X565155Y306002D01*
X564848Y306260D01*
X564657Y306570D01*
X564618Y306880D01*
X564695Y307242D01*
X564963Y307500D01*
X565232Y307603D01*
X565577D01*
G01X565232D02*
X565002Y307758D01*
X564810Y308017D01*
X564733Y308327D01*
X564810Y308637D01*
X565002Y308895D01*
X565347Y309050D01*
X565692Y308998D01*
X566037Y308792D01*
G01X558450Y417167D02*
X560950D01*
Y417833D01*
X560825Y418047D01*
X560658Y418180D01*
X560325Y418233D01*
X559992Y418180D01*
X559783Y418020D01*
X559658Y417833D01*
Y417167D01*
G01Y417833D02*
X558450Y418233D01*
G01X560533Y419393D02*
X560783Y419553D01*
X560908Y419740D01*
X560950Y419953D01*
X560867Y420220D01*
X560658Y420407D01*
X560408Y420460D01*
X560158Y420433D01*
X559950Y420327D01*
X559533Y419793D01*
X559242Y419553D01*
X558825Y419393D01*
X558450Y419340D01*
Y420460D01*
G01X558825Y421513D02*
X558617Y421673D01*
X558492Y421860D01*
X558450Y422100D01*
X558533Y422340D01*
X558700Y422527D01*
X558992Y422660D01*
X559325Y422687D01*
X559658Y422633D01*
X559867Y422500D01*
X560033Y422313D01*
X560075Y422127D01*
X560033Y421940D01*
X559867Y421700D01*
X560950Y421780D01*
Y422500D01*
G01X558450Y424300D02*
X558492Y424487D01*
X558617Y424700D01*
X558825Y424833D01*
X559117Y424887D01*
X559408Y424833D01*
X559658Y424673D01*
X559783Y424433D01*
Y424167D01*
X559867Y424007D01*
X560075Y423873D01*
X560367Y423820D01*
X560658Y423900D01*
X560867Y424087D01*
X560950Y424300D01*
X560867Y424513D01*
X560658Y424700D01*
X560367Y424780D01*
X560075Y424727D01*
X559867Y424593D01*
X559783Y424433D01*
Y424167D01*
X559658Y423927D01*
X559408Y423767D01*
X559117Y423713D01*
X558825Y423767D01*
X558617Y423900D01*
X558492Y424113D01*
X558450Y424300D01*
G01X582950Y61083D02*
X586050D01*
Y62042D01*
X585895Y62348D01*
X585688Y62540D01*
X585275Y62617D01*
X584862Y62540D01*
X584603Y62310D01*
X584448Y62042D01*
Y61083D01*
G01Y62042D02*
X582950Y62617D01*
G01X585533Y64222D02*
X585843Y64452D01*
X585998Y64720D01*
X586050Y65027D01*
X585947Y65410D01*
X585688Y65678D01*
X585378Y65755D01*
X585068Y65717D01*
X584810Y65563D01*
X584293Y64797D01*
X583932Y64452D01*
X583415Y64222D01*
X582950Y64145D01*
Y65755D01*
G01X585533Y67322D02*
X585843Y67552D01*
X585998Y67820D01*
X586050Y68127D01*
X585947Y68510D01*
X585688Y68778D01*
X585378Y68855D01*
X585068Y68817D01*
X584810Y68663D01*
X584293Y67897D01*
X583932Y67552D01*
X583415Y67322D01*
X582950Y67245D01*
Y68855D01*
G01Y71073D02*
X583622Y71150D01*
X584190Y71265D01*
X584707Y71418D01*
X585275Y71610D01*
X586050Y71917D01*
Y70383D01*
G01X583792Y84693D02*
X583947Y84463D01*
X584050Y84195D01*
Y83888D01*
X583895Y83543D01*
X583637Y83275D01*
X583327Y83083D01*
X582810Y82930D01*
X582345Y82892D01*
X581880Y82968D01*
X581570Y83083D01*
X581260Y83313D01*
X581053Y83582D01*
X580950Y83850D01*
Y84118D01*
X581053Y84387D01*
X581208Y84617D01*
X581415Y84808D01*
G01X583533Y86222D02*
X583843Y86452D01*
X583998Y86720D01*
X584050Y87027D01*
X583947Y87410D01*
X583688Y87678D01*
X583378Y87755D01*
X583068Y87717D01*
X582810Y87563D01*
X582293Y86797D01*
X581932Y86452D01*
X581415Y86222D01*
X580950Y86145D01*
Y87755D01*
G01X581312Y89398D02*
X581053Y89667D01*
X580950Y89973D01*
X581053Y90280D01*
X581363Y90548D01*
X581828Y90740D01*
X582293Y90817D01*
X582862D01*
X583327Y90740D01*
X583740Y90548D01*
X583947Y90318D01*
X584050Y90050D01*
X583947Y89743D01*
X583740Y89513D01*
X583430Y89360D01*
X583017Y89283D01*
X582655Y89360D01*
X582293Y89552D01*
X582087Y89782D01*
X582035Y90050D01*
X582138Y90357D01*
X582397Y90587D01*
X582862Y90817D01*
G01X581570Y92307D02*
X581208Y92537D01*
X581002Y92843D01*
X580950Y93188D01*
X581002Y93495D01*
X581260Y93802D01*
X581570Y93993D01*
X581880Y94032D01*
X582242Y93955D01*
X582500Y93687D01*
X582603Y93418D01*
Y93073D01*
G01Y93418D02*
X582758Y93648D01*
X583017Y93840D01*
X583327Y93917D01*
X583637Y93840D01*
X583895Y93648D01*
X584050Y93303D01*
X583998Y92958D01*
X583792Y92613D01*
G01X575950Y83083D02*
X579050D01*
Y84042D01*
X578895Y84348D01*
X578688Y84540D01*
X578275Y84617D01*
X577862Y84540D01*
X577603Y84310D01*
X577448Y84042D01*
Y83083D01*
G01Y84042D02*
X575950Y84617D01*
G01X578533Y86222D02*
X578843Y86452D01*
X578998Y86720D01*
X579050Y87027D01*
X578947Y87410D01*
X578688Y87678D01*
X578378Y87755D01*
X578068Y87717D01*
X577810Y87563D01*
X577293Y86797D01*
X576932Y86452D01*
X576415Y86222D01*
X575950Y86145D01*
Y87755D01*
G01X578533Y89322D02*
X578843Y89552D01*
X578998Y89820D01*
X579050Y90127D01*
X578947Y90510D01*
X578688Y90778D01*
X578378Y90855D01*
X578068Y90817D01*
X577810Y90663D01*
X577293Y89897D01*
X576932Y89552D01*
X576415Y89322D01*
X575950Y89245D01*
Y90855D01*
G01X576415Y92307D02*
X576157Y92537D01*
X576002Y92805D01*
X575950Y93150D01*
X576053Y93495D01*
X576260Y93763D01*
X576622Y93955D01*
X577035Y93993D01*
X577448Y93917D01*
X577707Y93725D01*
X577913Y93457D01*
X577965Y93188D01*
X577913Y92920D01*
X577707Y92575D01*
X579050Y92690D01*
Y93725D01*
G01X584950Y232583D02*
X588050D01*
Y233542D01*
X587895Y233848D01*
X587688Y234040D01*
X587275Y234117D01*
X586862Y234040D01*
X586603Y233810D01*
X586448Y233542D01*
Y232583D01*
G01Y233542D02*
X584950Y234117D01*
G01X587533Y235722D02*
X587843Y235952D01*
X587998Y236220D01*
X588050Y236527D01*
X587947Y236910D01*
X587688Y237178D01*
X587378Y237255D01*
X587068Y237217D01*
X586810Y237063D01*
X586293Y236297D01*
X585932Y235952D01*
X585415Y235722D01*
X584950Y235645D01*
Y237255D01*
G01X585415Y238707D02*
X585157Y238937D01*
X585002Y239205D01*
X584950Y239550D01*
X585053Y239895D01*
X585260Y240163D01*
X585622Y240355D01*
X586035Y240393D01*
X586448Y240317D01*
X586707Y240125D01*
X586913Y239857D01*
X586965Y239588D01*
X586913Y239320D01*
X586707Y238975D01*
X588050Y239090D01*
Y240125D01*
G01X584950Y242650D02*
X588050D01*
X587430Y242190D01*
G01X584950D02*
Y243110D01*
G01X580950Y232583D02*
X584050D01*
Y233542D01*
X583895Y233848D01*
X583688Y234040D01*
X583275Y234117D01*
X582862Y234040D01*
X582603Y233810D01*
X582448Y233542D01*
Y232583D01*
G01Y233542D02*
X580950Y234117D01*
G01X583533Y235722D02*
X583843Y235952D01*
X583998Y236220D01*
X584050Y236527D01*
X583947Y236910D01*
X583688Y237178D01*
X583378Y237255D01*
X583068Y237217D01*
X582810Y237063D01*
X582293Y236297D01*
X581932Y235952D01*
X581415Y235722D01*
X580950Y235645D01*
Y237255D01*
G01X581415Y238707D02*
X581157Y238937D01*
X581002Y239205D01*
X580950Y239550D01*
X581053Y239895D01*
X581260Y240163D01*
X581622Y240355D01*
X582035Y240393D01*
X582448Y240317D01*
X582707Y240125D01*
X582913Y239857D01*
X582965Y239588D01*
X582913Y239320D01*
X582707Y238975D01*
X584050Y239090D01*
Y240125D01*
G01X583533Y241922D02*
X583843Y242152D01*
X583998Y242420D01*
X584050Y242727D01*
X583947Y243110D01*
X583688Y243378D01*
X583378Y243455D01*
X583068Y243417D01*
X582810Y243263D01*
X582293Y242497D01*
X581932Y242152D01*
X581415Y241922D01*
X580950Y241845D01*
Y243455D01*
G01X580040Y274950D02*
Y278050D01*
X581458Y275828D01*
X579542D01*
G01X585792Y289743D02*
X585947Y289513D01*
X586050Y289245D01*
Y288938D01*
X585895Y288593D01*
X585637Y288325D01*
X585327Y288133D01*
X584810Y287980D01*
X584345Y287942D01*
X583880Y288018D01*
X583570Y288133D01*
X583260Y288363D01*
X583053Y288632D01*
X582950Y288900D01*
Y289168D01*
X583053Y289437D01*
X583208Y289667D01*
X583415Y289858D01*
G01X582950Y291233D02*
X586050D01*
Y292192D01*
X585895Y292498D01*
X585688Y292690D01*
X585275Y292767D01*
X584862Y292690D01*
X584603Y292460D01*
X584448Y292192D01*
Y291233D01*
G01Y292192D02*
X582950Y292767D01*
G01X584242Y294372D02*
X584603Y294640D01*
X584810Y294870D01*
X584913Y295177D01*
X584810Y295445D01*
X584603Y295637D01*
X584293Y295790D01*
X583932Y295828D01*
X583622Y295790D01*
X583312Y295637D01*
X583053Y295407D01*
X582950Y295138D01*
X583053Y294832D01*
X583363Y294563D01*
X583828Y294410D01*
X584345Y294372D01*
X585017Y294448D01*
X585378Y294563D01*
X585740Y294755D01*
X585998Y295023D01*
X586050Y295292D01*
X585947Y295560D01*
X585688Y295752D01*
G01X576040Y305950D02*
Y309050D01*
X577458Y306828D01*
X575542D01*
G01X590367Y388950D02*
Y392050D01*
X589408D01*
X589102Y391895D01*
X588910Y391688D01*
X588833Y391275D01*
X588910Y390862D01*
X589140Y390603D01*
X589408Y390448D01*
X590367D01*
G01X589408D02*
X588833Y388950D01*
G01X586500D02*
Y392050D01*
X586960Y391430D01*
G01Y388950D02*
X586040D01*
G01X584128Y390242D02*
X583860Y390603D01*
X583630Y390810D01*
X583323Y390913D01*
X583055Y390810D01*
X582863Y390603D01*
X582710Y390293D01*
X582672Y389932D01*
X582710Y389622D01*
X582863Y389312D01*
X583093Y389053D01*
X583362Y388950D01*
X583668Y389053D01*
X583937Y389363D01*
X584090Y389828D01*
X584128Y390345D01*
X584052Y391017D01*
X583937Y391378D01*
X583745Y391740D01*
X583477Y391998D01*
X583208Y392050D01*
X582940Y391947D01*
X582748Y391688D01*
G01X590367Y384450D02*
Y387550D01*
X589408D01*
X589102Y387395D01*
X588910Y387188D01*
X588833Y386775D01*
X588910Y386362D01*
X589140Y386103D01*
X589408Y385948D01*
X590367D01*
G01X589408D02*
X588833Y384450D01*
G01X586500D02*
Y387550D01*
X586960Y386930D01*
G01Y384450D02*
X586040D01*
G01X583400Y387550D02*
X583707Y387447D01*
X583937Y387188D01*
X584090Y386878D01*
X584205Y386465D01*
X584243Y386000D01*
X584205Y385535D01*
X584090Y385122D01*
X583937Y384812D01*
X583707Y384553D01*
X583400Y384450D01*
X583093Y384553D01*
X582863Y384812D01*
X582710Y385122D01*
X582595Y385535D01*
X582557Y386000D01*
X582595Y386465D01*
X582710Y386878D01*
X582863Y387188D01*
X583093Y387447D01*
X583400Y387550D01*
G01X588417Y397950D02*
Y401050D01*
X587458D01*
X587152Y400895D01*
X586960Y400688D01*
X586883Y400275D01*
X586960Y399862D01*
X587190Y399603D01*
X587458Y399448D01*
X588417D01*
G01X587458D02*
X586883Y397950D01*
G01X585278Y400533D02*
X585048Y400843D01*
X584780Y400998D01*
X584473Y401050D01*
X584090Y400947D01*
X583822Y400688D01*
X583745Y400378D01*
X583783Y400068D01*
X583937Y399810D01*
X584703Y399293D01*
X585048Y398932D01*
X585278Y398415D01*
X585355Y397950D01*
X583745D01*
G01X582293Y398415D02*
X582063Y398157D01*
X581795Y398002D01*
X581450Y397950D01*
X581105Y398053D01*
X580837Y398260D01*
X580645Y398622D01*
X580607Y399035D01*
X580683Y399448D01*
X580875Y399707D01*
X581143Y399913D01*
X581412Y399965D01*
X581680Y399913D01*
X582025Y399707D01*
X581910Y401050D01*
X580875D01*
G01X579078Y399242D02*
X578810Y399603D01*
X578580Y399810D01*
X578273Y399913D01*
X578005Y399810D01*
X577813Y399603D01*
X577660Y399293D01*
X577622Y398932D01*
X577660Y398622D01*
X577813Y398312D01*
X578043Y398053D01*
X578312Y397950D01*
X578618Y398053D01*
X578887Y398363D01*
X579040Y398828D01*
X579078Y399345D01*
X579002Y400017D01*
X578887Y400378D01*
X578695Y400740D01*
X578427Y400998D01*
X578158Y401050D01*
X577890Y400947D01*
X577698Y400688D01*
G01X588417Y393950D02*
Y397050D01*
X587458D01*
X587152Y396895D01*
X586960Y396688D01*
X586883Y396275D01*
X586960Y395862D01*
X587190Y395603D01*
X587458Y395448D01*
X588417D01*
G01X587458D02*
X586883Y393950D01*
G01X585278Y396533D02*
X585048Y396843D01*
X584780Y396998D01*
X584473Y397050D01*
X584090Y396947D01*
X583822Y396688D01*
X583745Y396378D01*
X583783Y396068D01*
X583937Y395810D01*
X584703Y395293D01*
X585048Y394932D01*
X585278Y394415D01*
X585355Y393950D01*
X583745D01*
G01X582178Y395242D02*
X581910Y395603D01*
X581680Y395810D01*
X581373Y395913D01*
X581105Y395810D01*
X580913Y395603D01*
X580760Y395293D01*
X580722Y394932D01*
X580760Y394622D01*
X580913Y394312D01*
X581143Y394053D01*
X581412Y393950D01*
X581718Y394053D01*
X581987Y394363D01*
X582140Y394828D01*
X582178Y395345D01*
X582102Y396017D01*
X581987Y396378D01*
X581795Y396740D01*
X581527Y396998D01*
X581258Y397050D01*
X580990Y396947D01*
X580798Y396688D01*
G01X579078Y396533D02*
X578848Y396843D01*
X578580Y396998D01*
X578273Y397050D01*
X577890Y396947D01*
X577622Y396688D01*
X577545Y396378D01*
X577583Y396068D01*
X577737Y395810D01*
X578503Y395293D01*
X578848Y394932D01*
X579078Y394415D01*
X579155Y393950D01*
X577545D01*
G01X570250Y402167D02*
X572750D01*
Y402833D01*
X572625Y403047D01*
X572458Y403180D01*
X572125Y403233D01*
X571792Y403180D01*
X571583Y403020D01*
X571458Y402833D01*
Y402167D01*
G01Y402833D02*
X570250Y403233D01*
G01Y404900D02*
X572750D01*
X572250Y404580D01*
G01X570250D02*
Y405220D01*
G01Y407100D02*
X570292Y407287D01*
X570417Y407500D01*
X570625Y407633D01*
X570917Y407687D01*
X571208Y407633D01*
X571458Y407473D01*
X571583Y407233D01*
Y406967D01*
X571667Y406807D01*
X571875Y406673D01*
X572167Y406620D01*
X572458Y406700D01*
X572667Y406887D01*
X572750Y407100D01*
X572667Y407313D01*
X572458Y407500D01*
X572167Y407580D01*
X571875Y407527D01*
X571667Y407393D01*
X571583Y407233D01*
Y406967D01*
X571458Y406727D01*
X571208Y406567D01*
X570917Y406513D01*
X570625Y406567D01*
X570417Y406700D01*
X570292Y406913D01*
X570250Y407100D01*
G01X572750Y409300D02*
X572667Y409087D01*
X572458Y408927D01*
X572208Y408820D01*
X571875Y408740D01*
X571500Y408713D01*
X571125Y408740D01*
X570792Y408820D01*
X570542Y408927D01*
X570333Y409087D01*
X570250Y409300D01*
X570333Y409513D01*
X570542Y409673D01*
X570792Y409780D01*
X571125Y409860D01*
X571500Y409887D01*
X571875Y409860D01*
X572208Y409780D01*
X572458Y409673D01*
X572667Y409513D01*
X572750Y409300D01*
G01X585450Y418583D02*
X588550D01*
Y419542D01*
X588395Y419848D01*
X588188Y420040D01*
X587775Y420117D01*
X587362Y420040D01*
X587103Y419810D01*
X586948Y419542D01*
Y418583D01*
G01Y419542D02*
X585450Y420117D01*
G01X588033Y421722D02*
X588343Y421952D01*
X588498Y422220D01*
X588550Y422527D01*
X588447Y422910D01*
X588188Y423178D01*
X587878Y423255D01*
X587568Y423217D01*
X587310Y423063D01*
X586793Y422297D01*
X586432Y421952D01*
X585915Y421722D01*
X585450Y421645D01*
Y423255D01*
G01X586742Y424822D02*
X587103Y425090D01*
X587310Y425320D01*
X587413Y425627D01*
X587310Y425895D01*
X587103Y426087D01*
X586793Y426240D01*
X586432Y426278D01*
X586122Y426240D01*
X585812Y426087D01*
X585553Y425857D01*
X585450Y425588D01*
X585553Y425282D01*
X585863Y425013D01*
X586328Y424860D01*
X586845Y424822D01*
X587517Y424898D01*
X587878Y425013D01*
X588240Y425205D01*
X588498Y425473D01*
X588550Y425742D01*
X588447Y426010D01*
X588188Y426202D01*
G01X585450Y428650D02*
X588550D01*
X587930Y428190D01*
G01X585450D02*
Y429110D01*
G01X570450Y417167D02*
X572950D01*
Y417833D01*
X572825Y418047D01*
X572658Y418180D01*
X572325Y418233D01*
X571992Y418180D01*
X571783Y418020D01*
X571658Y417833D01*
Y417167D01*
G01Y417833D02*
X570450Y418233D01*
G01X572533Y419393D02*
X572783Y419553D01*
X572908Y419740D01*
X572950Y419953D01*
X572867Y420220D01*
X572658Y420407D01*
X572408Y420460D01*
X572158Y420433D01*
X571950Y420327D01*
X571533Y419793D01*
X571242Y419553D01*
X570825Y419393D01*
X570450Y419340D01*
Y420460D01*
G01X570825Y421513D02*
X570617Y421673D01*
X570492Y421860D01*
X570450Y422100D01*
X570533Y422340D01*
X570700Y422527D01*
X570992Y422660D01*
X571325Y422687D01*
X571658Y422633D01*
X571867Y422500D01*
X572033Y422313D01*
X572075Y422127D01*
X572033Y421940D01*
X571867Y421700D01*
X572950Y421780D01*
Y422500D01*
G01X570742Y423847D02*
X570533Y424033D01*
X570450Y424247D01*
X570533Y424460D01*
X570783Y424647D01*
X571158Y424780D01*
X571533Y424833D01*
X571992D01*
X572367Y424780D01*
X572700Y424647D01*
X572867Y424487D01*
X572950Y424300D01*
X572867Y424087D01*
X572700Y423927D01*
X572450Y423820D01*
X572117Y423767D01*
X571825Y423820D01*
X571533Y423953D01*
X571367Y424113D01*
X571325Y424300D01*
X571408Y424513D01*
X571617Y424673D01*
X571992Y424833D01*
G01X605917Y122950D02*
Y126050D01*
X604958D01*
X604652Y125895D01*
X604460Y125688D01*
X604383Y125275D01*
X604460Y124862D01*
X604690Y124603D01*
X604958Y124448D01*
X605917D01*
G01X604958D02*
X604383Y122950D01*
G01X601590D02*
Y126050D01*
X603008Y123828D01*
X601092D01*
G01X599793Y123570D02*
X599563Y123208D01*
X599257Y123002D01*
X598912Y122950D01*
X598605Y123002D01*
X598298Y123260D01*
X598107Y123570D01*
X598068Y123880D01*
X598145Y124242D01*
X598413Y124500D01*
X598682Y124603D01*
X599027D01*
G01X598682D02*
X598452Y124758D01*
X598260Y125017D01*
X598183Y125327D01*
X598260Y125637D01*
X598452Y125895D01*
X598797Y126050D01*
X599142Y125998D01*
X599487Y125792D01*
G01X595850Y122950D02*
Y126050D01*
X596310Y125430D01*
G01Y122950D02*
X595390D01*
G01X605917Y126950D02*
Y130050D01*
X604958D01*
X604652Y129895D01*
X604460Y129688D01*
X604383Y129275D01*
X604460Y128862D01*
X604690Y128603D01*
X604958Y128448D01*
X605917D01*
G01X604958D02*
X604383Y126950D01*
G01X601590D02*
Y130050D01*
X603008Y127828D01*
X601092D01*
G01X599793Y127570D02*
X599563Y127208D01*
X599257Y127002D01*
X598912Y126950D01*
X598605Y127002D01*
X598298Y127260D01*
X598107Y127570D01*
X598068Y127880D01*
X598145Y128242D01*
X598413Y128500D01*
X598682Y128603D01*
X599027D01*
G01X598682D02*
X598452Y128758D01*
X598260Y129017D01*
X598183Y129327D01*
X598260Y129637D01*
X598452Y129895D01*
X598797Y130050D01*
X599142Y129998D01*
X599487Y129792D01*
G01X596578Y129533D02*
X596348Y129843D01*
X596080Y129998D01*
X595773Y130050D01*
X595390Y129947D01*
X595122Y129688D01*
X595045Y129378D01*
X595083Y129068D01*
X595237Y128810D01*
X596003Y128293D01*
X596348Y127932D01*
X596578Y127415D01*
X596655Y126950D01*
X595045D01*
G01X605917Y130950D02*
Y134050D01*
X604958D01*
X604652Y133895D01*
X604460Y133688D01*
X604383Y133275D01*
X604460Y132862D01*
X604690Y132603D01*
X604958Y132448D01*
X605917D01*
G01X604958D02*
X604383Y130950D01*
G01X601590D02*
Y134050D01*
X603008Y131828D01*
X601092D01*
G01X599793Y131570D02*
X599563Y131208D01*
X599257Y131002D01*
X598912Y130950D01*
X598605Y131002D01*
X598298Y131260D01*
X598107Y131570D01*
X598068Y131880D01*
X598145Y132242D01*
X598413Y132500D01*
X598682Y132603D01*
X599027D01*
G01X598682D02*
X598452Y132758D01*
X598260Y133017D01*
X598183Y133327D01*
X598260Y133637D01*
X598452Y133895D01*
X598797Y134050D01*
X599142Y133998D01*
X599487Y133792D01*
G01X596693Y131570D02*
X596463Y131208D01*
X596157Y131002D01*
X595812Y130950D01*
X595505Y131002D01*
X595198Y131260D01*
X595007Y131570D01*
X594968Y131880D01*
X595045Y132242D01*
X595313Y132500D01*
X595582Y132603D01*
X595927D01*
G01X595582D02*
X595352Y132758D01*
X595160Y133017D01*
X595083Y133327D01*
X595160Y133637D01*
X595352Y133895D01*
X595697Y134050D01*
X596042Y133998D01*
X596387Y133792D01*
G01X605917Y135450D02*
Y138550D01*
X604958D01*
X604652Y138395D01*
X604460Y138188D01*
X604383Y137775D01*
X604460Y137362D01*
X604690Y137103D01*
X604958Y136948D01*
X605917D01*
G01X604958D02*
X604383Y135450D01*
G01X601590D02*
Y138550D01*
X603008Y136328D01*
X601092D01*
G01X599793Y136070D02*
X599563Y135708D01*
X599257Y135502D01*
X598912Y135450D01*
X598605Y135502D01*
X598298Y135760D01*
X598107Y136070D01*
X598068Y136380D01*
X598145Y136742D01*
X598413Y137000D01*
X598682Y137103D01*
X599027D01*
G01X598682D02*
X598452Y137258D01*
X598260Y137517D01*
X598183Y137827D01*
X598260Y138137D01*
X598452Y138395D01*
X598797Y138550D01*
X599142Y138498D01*
X599487Y138292D01*
G01X595390Y135450D02*
Y138550D01*
X596808Y136328D01*
X594892D01*
G01X587450Y204133D02*
X590550D01*
Y205092D01*
X590395Y205398D01*
X590188Y205590D01*
X589775Y205667D01*
X589362Y205590D01*
X589103Y205360D01*
X588948Y205092D01*
Y204133D01*
G01Y205092D02*
X587450Y205667D01*
G01X588742Y207272D02*
X589103Y207540D01*
X589310Y207770D01*
X589413Y208077D01*
X589310Y208345D01*
X589103Y208537D01*
X588793Y208690D01*
X588432Y208728D01*
X588122Y208690D01*
X587812Y208537D01*
X587553Y208307D01*
X587450Y208038D01*
X587553Y207732D01*
X587863Y207463D01*
X588328Y207310D01*
X588845Y207272D01*
X589517Y207348D01*
X589878Y207463D01*
X590240Y207655D01*
X590498Y207923D01*
X590550Y208192D01*
X590447Y208460D01*
X590188Y208652D01*
G01X587450Y211560D02*
X590550D01*
X588328Y210142D01*
Y212058D01*
G01X591450Y204133D02*
X594550D01*
Y205092D01*
X594395Y205398D01*
X594188Y205590D01*
X593775Y205667D01*
X593362Y205590D01*
X593103Y205360D01*
X592948Y205092D01*
Y204133D01*
G01Y205092D02*
X591450Y205667D01*
G01X592742Y207272D02*
X593103Y207540D01*
X593310Y207770D01*
X593413Y208077D01*
X593310Y208345D01*
X593103Y208537D01*
X592793Y208690D01*
X592432Y208728D01*
X592122Y208690D01*
X591812Y208537D01*
X591553Y208307D01*
X591450Y208038D01*
X591553Y207732D01*
X591863Y207463D01*
X592328Y207310D01*
X592845Y207272D01*
X593517Y207348D01*
X593878Y207463D01*
X594240Y207655D01*
X594498Y207923D01*
X594550Y208192D01*
X594447Y208460D01*
X594188Y208652D01*
G01X591812Y210448D02*
X591553Y210717D01*
X591450Y211023D01*
X591553Y211330D01*
X591863Y211598D01*
X592328Y211790D01*
X592793Y211867D01*
X593362D01*
X593827Y211790D01*
X594240Y211598D01*
X594447Y211368D01*
X594550Y211100D01*
X594447Y210793D01*
X594240Y210563D01*
X593930Y210410D01*
X593517Y210333D01*
X593155Y210410D01*
X592793Y210602D01*
X592587Y210832D01*
X592535Y211100D01*
X592638Y211407D01*
X592897Y211637D01*
X593362Y211867D01*
G01X597950Y203083D02*
X601050D01*
Y204042D01*
X600895Y204348D01*
X600688Y204540D01*
X600275Y204617D01*
X599862Y204540D01*
X599603Y204310D01*
X599448Y204042D01*
Y203083D01*
G01Y204042D02*
X597950Y204617D01*
G01X598570Y206107D02*
X598208Y206337D01*
X598002Y206643D01*
X597950Y206988D01*
X598002Y207295D01*
X598260Y207602D01*
X598570Y207793D01*
X598880Y207832D01*
X599242Y207755D01*
X599500Y207487D01*
X599603Y207218D01*
Y206873D01*
G01Y207218D02*
X599758Y207448D01*
X600017Y207640D01*
X600327Y207717D01*
X600637Y207640D01*
X600895Y207448D01*
X601050Y207103D01*
X600998Y206758D01*
X600792Y206413D01*
G01X601050Y210050D02*
X600947Y209743D01*
X600688Y209513D01*
X600378Y209360D01*
X599965Y209245D01*
X599500Y209207D01*
X599035Y209245D01*
X598622Y209360D01*
X598312Y209513D01*
X598053Y209743D01*
X597950Y210050D01*
X598053Y210357D01*
X598312Y210587D01*
X598622Y210740D01*
X599035Y210855D01*
X599500Y210893D01*
X599965Y210855D01*
X600378Y210740D01*
X600688Y210587D01*
X600947Y210357D01*
X601050Y210050D01*
G01Y213150D02*
X600947Y212843D01*
X600688Y212613D01*
X600378Y212460D01*
X599965Y212345D01*
X599500Y212307D01*
X599035Y212345D01*
X598622Y212460D01*
X598312Y212613D01*
X598053Y212843D01*
X597950Y213150D01*
X598053Y213457D01*
X598312Y213687D01*
X598622Y213840D01*
X599035Y213955D01*
X599500Y213993D01*
X599965Y213955D01*
X600378Y213840D01*
X600688Y213687D01*
X600947Y213457D01*
X601050Y213150D01*
G01X605367Y264450D02*
Y267550D01*
X604408D01*
X604102Y267395D01*
X603910Y267188D01*
X603833Y266775D01*
X603910Y266362D01*
X604140Y266103D01*
X604408Y265948D01*
X605367D01*
G01X604408D02*
X603833Y264450D01*
G01X601500D02*
X601232Y264502D01*
X600925Y264657D01*
X600733Y264915D01*
X600657Y265277D01*
X600733Y265638D01*
X600963Y265948D01*
X601308Y266103D01*
X601692D01*
X601922Y266207D01*
X602113Y266465D01*
X602190Y266827D01*
X602075Y267188D01*
X601807Y267447D01*
X601500Y267550D01*
X601193Y267447D01*
X600925Y267188D01*
X600810Y266827D01*
X600887Y266465D01*
X601078Y266207D01*
X601308Y266103D01*
X601692D01*
X602037Y265948D01*
X602267Y265638D01*
X602343Y265277D01*
X602267Y264915D01*
X602075Y264657D01*
X601768Y264502D01*
X601500Y264450D01*
G01X598400D02*
Y267550D01*
X598860Y266930D01*
G01Y264450D02*
X597940D01*
G01X605367Y281450D02*
Y284550D01*
X604408D01*
X604102Y284395D01*
X603910Y284188D01*
X603833Y283775D01*
X603910Y283362D01*
X604140Y283103D01*
X604408Y282948D01*
X605367D01*
G01X604408D02*
X603833Y281450D01*
G01X601500D02*
X601232Y281502D01*
X600925Y281657D01*
X600733Y281915D01*
X600657Y282277D01*
X600733Y282638D01*
X600963Y282948D01*
X601308Y283103D01*
X601692D01*
X601922Y283207D01*
X602113Y283465D01*
X602190Y283827D01*
X602075Y284188D01*
X601807Y284447D01*
X601500Y284550D01*
X601193Y284447D01*
X600925Y284188D01*
X600810Y283827D01*
X600887Y283465D01*
X601078Y283207D01*
X601308Y283103D01*
X601692D01*
X602037Y282948D01*
X602267Y282638D01*
X602343Y282277D01*
X602267Y281915D01*
X602075Y281657D01*
X601768Y281502D01*
X601500Y281450D01*
G01X599128Y284033D02*
X598898Y284343D01*
X598630Y284498D01*
X598323Y284550D01*
X597940Y284447D01*
X597672Y284188D01*
X597595Y283878D01*
X597633Y283568D01*
X597787Y283310D01*
X598553Y282793D01*
X598898Y282432D01*
X599128Y281915D01*
X599205Y281450D01*
X597595D01*
G01X593950Y400083D02*
X597050D01*
Y401042D01*
X596895Y401348D01*
X596688Y401540D01*
X596275Y401617D01*
X595862Y401540D01*
X595603Y401310D01*
X595448Y401042D01*
Y400083D01*
G01Y401042D02*
X593950Y401617D01*
G01Y403950D02*
X597050D01*
X596430Y403490D01*
G01X593950D02*
Y404410D01*
G01Y407050D02*
X597050D01*
X596430Y406590D01*
G01X593950D02*
Y407510D01*
G01Y410150D02*
X594002Y410418D01*
X594157Y410725D01*
X594415Y410917D01*
X594777Y410993D01*
X595138Y410917D01*
X595448Y410687D01*
X595603Y410342D01*
Y409958D01*
X595707Y409728D01*
X595965Y409537D01*
X596327Y409460D01*
X596688Y409575D01*
X596947Y409843D01*
X597050Y410150D01*
X596947Y410457D01*
X596688Y410725D01*
X596327Y410840D01*
X595965Y410763D01*
X595707Y410572D01*
X595603Y410342D01*
Y409958D01*
X595448Y409613D01*
X595138Y409383D01*
X594777Y409307D01*
X594415Y409383D01*
X594157Y409575D01*
X594002Y409882D01*
X593950Y410150D01*
G01X591950Y420583D02*
X595050D01*
Y421542D01*
X594895Y421848D01*
X594688Y422040D01*
X594275Y422117D01*
X593862Y422040D01*
X593603Y421810D01*
X593448Y421542D01*
Y420583D01*
G01Y421542D02*
X591950Y422117D01*
G01X594533Y423722D02*
X594843Y423952D01*
X594998Y424220D01*
X595050Y424527D01*
X594947Y424910D01*
X594688Y425178D01*
X594378Y425255D01*
X594068Y425217D01*
X593810Y425063D01*
X593293Y424297D01*
X592932Y423952D01*
X592415Y423722D01*
X591950Y423645D01*
Y425255D01*
G01Y427473D02*
X592622Y427550D01*
X593190Y427665D01*
X593707Y427818D01*
X594275Y428010D01*
X595050Y428317D01*
Y426783D01*
G01X592312Y429998D02*
X592053Y430267D01*
X591950Y430573D01*
X592053Y430880D01*
X592363Y431148D01*
X592828Y431340D01*
X593293Y431417D01*
X593862D01*
X594327Y431340D01*
X594740Y431148D01*
X594947Y430918D01*
X595050Y430650D01*
X594947Y430343D01*
X594740Y430113D01*
X594430Y429960D01*
X594017Y429883D01*
X593655Y429960D01*
X593293Y430152D01*
X593087Y430382D01*
X593035Y430650D01*
X593138Y430957D01*
X593397Y431187D01*
X593862Y431417D01*
G01X619917Y123450D02*
Y126550D01*
X618958D01*
X618652Y126395D01*
X618460Y126188D01*
X618383Y125775D01*
X618460Y125362D01*
X618690Y125103D01*
X618958Y124948D01*
X619917D01*
G01X618958D02*
X618383Y123450D01*
G01X616893Y124070D02*
X616663Y123708D01*
X616357Y123502D01*
X616012Y123450D01*
X615705Y123502D01*
X615398Y123760D01*
X615207Y124070D01*
X615168Y124380D01*
X615245Y124742D01*
X615513Y125000D01*
X615782Y125103D01*
X616127D01*
G01X615782D02*
X615552Y125258D01*
X615360Y125517D01*
X615283Y125827D01*
X615360Y126137D01*
X615552Y126395D01*
X615897Y126550D01*
X616242Y126498D01*
X616587Y126292D01*
G01X613678Y126033D02*
X613448Y126343D01*
X613180Y126498D01*
X612873Y126550D01*
X612490Y126447D01*
X612222Y126188D01*
X612145Y125878D01*
X612183Y125568D01*
X612337Y125310D01*
X613103Y124793D01*
X613448Y124432D01*
X613678Y123915D01*
X613755Y123450D01*
X612145D01*
G01X610502Y123812D02*
X610233Y123553D01*
X609927Y123450D01*
X609620Y123553D01*
X609352Y123863D01*
X609160Y124328D01*
X609083Y124793D01*
Y125362D01*
X609160Y125827D01*
X609352Y126240D01*
X609582Y126447D01*
X609850Y126550D01*
X610157Y126447D01*
X610387Y126240D01*
X610540Y125930D01*
X610617Y125517D01*
X610540Y125155D01*
X610348Y124793D01*
X610118Y124587D01*
X609850Y124535D01*
X609543Y124638D01*
X609313Y124897D01*
X609083Y125362D01*
G01X619917Y127450D02*
Y130550D01*
X618958D01*
X618652Y130395D01*
X618460Y130188D01*
X618383Y129775D01*
X618460Y129362D01*
X618690Y129103D01*
X618958Y128948D01*
X619917D01*
G01X618958D02*
X618383Y127450D01*
G01X615590D02*
Y130550D01*
X617008Y128328D01*
X615092D01*
G01X613678Y130033D02*
X613448Y130343D01*
X613180Y130498D01*
X612873Y130550D01*
X612490Y130447D01*
X612222Y130188D01*
X612145Y129878D01*
X612183Y129568D01*
X612337Y129310D01*
X613103Y128793D01*
X613448Y128432D01*
X613678Y127915D01*
X613755Y127450D01*
X612145D01*
G01X609850D02*
X609582Y127502D01*
X609275Y127657D01*
X609083Y127915D01*
X609007Y128277D01*
X609083Y128638D01*
X609313Y128948D01*
X609658Y129103D01*
X610042D01*
X610272Y129207D01*
X610463Y129465D01*
X610540Y129827D01*
X610425Y130188D01*
X610157Y130447D01*
X609850Y130550D01*
X609543Y130447D01*
X609275Y130188D01*
X609160Y129827D01*
X609237Y129465D01*
X609428Y129207D01*
X609658Y129103D01*
X610042D01*
X610387Y128948D01*
X610617Y128638D01*
X610693Y128277D01*
X610617Y127915D01*
X610425Y127657D01*
X610118Y127502D01*
X609850Y127450D01*
G01X619917Y131450D02*
Y134550D01*
X618958D01*
X618652Y134395D01*
X618460Y134188D01*
X618383Y133775D01*
X618460Y133362D01*
X618690Y133103D01*
X618958Y132948D01*
X619917D01*
G01X618958D02*
X618383Y131450D01*
G01X615590D02*
Y134550D01*
X617008Y132328D01*
X615092D01*
G01X613678Y134033D02*
X613448Y134343D01*
X613180Y134498D01*
X612873Y134550D01*
X612490Y134447D01*
X612222Y134188D01*
X612145Y133878D01*
X612183Y133568D01*
X612337Y133310D01*
X613103Y132793D01*
X613448Y132432D01*
X613678Y131915D01*
X613755Y131450D01*
X612145D01*
G01X610502Y131812D02*
X610233Y131553D01*
X609927Y131450D01*
X609620Y131553D01*
X609352Y131863D01*
X609160Y132328D01*
X609083Y132793D01*
Y133362D01*
X609160Y133827D01*
X609352Y134240D01*
X609582Y134447D01*
X609850Y134550D01*
X610157Y134447D01*
X610387Y134240D01*
X610540Y133930D01*
X610617Y133517D01*
X610540Y133155D01*
X610348Y132793D01*
X610118Y132587D01*
X609850Y132535D01*
X609543Y132638D01*
X609313Y132897D01*
X609083Y133362D01*
G01X619917Y135450D02*
Y138550D01*
X618958D01*
X618652Y138395D01*
X618460Y138188D01*
X618383Y137775D01*
X618460Y137362D01*
X618690Y137103D01*
X618958Y136948D01*
X619917D01*
G01X618958D02*
X618383Y135450D01*
G01X615590D02*
Y138550D01*
X617008Y136328D01*
X615092D01*
G01X613793Y136070D02*
X613563Y135708D01*
X613257Y135502D01*
X612912Y135450D01*
X612605Y135502D01*
X612298Y135760D01*
X612107Y136070D01*
X612068Y136380D01*
X612145Y136742D01*
X612413Y137000D01*
X612682Y137103D01*
X613027D01*
G01X612682D02*
X612452Y137258D01*
X612260Y137517D01*
X612183Y137827D01*
X612260Y138137D01*
X612452Y138395D01*
X612797Y138550D01*
X613142Y138498D01*
X613487Y138292D01*
G01X609850Y138550D02*
X610157Y138447D01*
X610387Y138188D01*
X610540Y137878D01*
X610655Y137465D01*
X610693Y137000D01*
X610655Y136535D01*
X610540Y136122D01*
X610387Y135812D01*
X610157Y135553D01*
X609850Y135450D01*
X609543Y135553D01*
X609313Y135812D01*
X609160Y136122D01*
X609045Y136535D01*
X609007Y137000D01*
X609045Y137465D01*
X609160Y137878D01*
X609313Y138188D01*
X609543Y138447D01*
X609850Y138550D01*
G01X604950Y203133D02*
X608050D01*
Y204092D01*
X607895Y204398D01*
X607688Y204590D01*
X607275Y204667D01*
X606862Y204590D01*
X606603Y204360D01*
X606448Y204092D01*
Y203133D01*
G01Y204092D02*
X604950Y204667D01*
G01X606242Y206272D02*
X606603Y206540D01*
X606810Y206770D01*
X606913Y207077D01*
X606810Y207345D01*
X606603Y207537D01*
X606293Y207690D01*
X605932Y207728D01*
X605622Y207690D01*
X605312Y207537D01*
X605053Y207307D01*
X604950Y207038D01*
X605053Y206732D01*
X605363Y206463D01*
X605828Y206310D01*
X606345Y206272D01*
X607017Y206348D01*
X607378Y206463D01*
X607740Y206655D01*
X607998Y206923D01*
X608050Y207192D01*
X607947Y207460D01*
X607688Y207652D01*
G01X605415Y209257D02*
X605157Y209487D01*
X605002Y209755D01*
X604950Y210100D01*
X605053Y210445D01*
X605260Y210713D01*
X605622Y210905D01*
X606035Y210943D01*
X606448Y210867D01*
X606707Y210675D01*
X606913Y210407D01*
X606965Y210138D01*
X606913Y209870D01*
X606707Y209525D01*
X608050Y209640D01*
Y210675D01*
G01X617950Y401083D02*
X621050D01*
Y402042D01*
X620895Y402348D01*
X620688Y402540D01*
X620275Y402617D01*
X619862Y402540D01*
X619603Y402310D01*
X619448Y402042D01*
Y401083D01*
G01Y402042D02*
X617950Y402617D01*
G01Y404950D02*
X621050D01*
X620430Y404490D01*
G01X617950D02*
Y405410D01*
G01X619242Y407322D02*
X619603Y407590D01*
X619810Y407820D01*
X619913Y408127D01*
X619810Y408395D01*
X619603Y408587D01*
X619293Y408740D01*
X618932Y408778D01*
X618622Y408740D01*
X618312Y408587D01*
X618053Y408357D01*
X617950Y408088D01*
X618053Y407782D01*
X618363Y407513D01*
X618828Y407360D01*
X619345Y407322D01*
X620017Y407398D01*
X620378Y407513D01*
X620740Y407705D01*
X620998Y407973D01*
X621050Y408242D01*
X620947Y408510D01*
X620688Y408702D01*
G01X618312Y410498D02*
X618053Y410767D01*
X617950Y411073D01*
X618053Y411380D01*
X618363Y411648D01*
X618828Y411840D01*
X619293Y411917D01*
X619862D01*
X620327Y411840D01*
X620740Y411648D01*
X620947Y411418D01*
X621050Y411150D01*
X620947Y410843D01*
X620740Y410613D01*
X620430Y410460D01*
X620017Y410383D01*
X619655Y410460D01*
X619293Y410652D01*
X619087Y410882D01*
X619035Y411150D01*
X619138Y411457D01*
X619397Y411687D01*
X619862Y411917D01*
G01X605450Y400583D02*
X608550D01*
Y401542D01*
X608395Y401848D01*
X608188Y402040D01*
X607775Y402117D01*
X607362Y402040D01*
X607103Y401810D01*
X606948Y401542D01*
Y400583D01*
G01Y401542D02*
X605450Y402117D01*
G01Y404450D02*
X608550D01*
X607930Y403990D01*
G01X605450D02*
Y404910D01*
G01Y407550D02*
X608550D01*
X607930Y407090D01*
G01X605450D02*
Y408010D01*
G01X605812Y409998D02*
X605553Y410267D01*
X605450Y410573D01*
X605553Y410880D01*
X605863Y411148D01*
X606328Y411340D01*
X606793Y411417D01*
X607362D01*
X607827Y411340D01*
X608240Y411148D01*
X608447Y410918D01*
X608550Y410650D01*
X608447Y410343D01*
X608240Y410113D01*
X607930Y409960D01*
X607517Y409883D01*
X607155Y409960D01*
X606793Y410152D01*
X606587Y410382D01*
X606535Y410650D01*
X606638Y410957D01*
X606897Y411187D01*
X607362Y411417D01*
G01X617450Y420083D02*
X620550D01*
Y421042D01*
X620395Y421348D01*
X620188Y421540D01*
X619775Y421617D01*
X619362Y421540D01*
X619103Y421310D01*
X618948Y421042D01*
Y420083D01*
G01Y421042D02*
X617450Y421617D01*
G01X620033Y423222D02*
X620343Y423452D01*
X620498Y423720D01*
X620550Y424027D01*
X620447Y424410D01*
X620188Y424678D01*
X619878Y424755D01*
X619568Y424717D01*
X619310Y424563D01*
X618793Y423797D01*
X618432Y423452D01*
X617915Y423222D01*
X617450Y423145D01*
Y424755D01*
G01Y427050D02*
X617502Y427318D01*
X617657Y427625D01*
X617915Y427817D01*
X618277Y427893D01*
X618638Y427817D01*
X618948Y427587D01*
X619103Y427242D01*
Y426858D01*
X619207Y426628D01*
X619465Y426437D01*
X619827Y426360D01*
X620188Y426475D01*
X620447Y426743D01*
X620550Y427050D01*
X620447Y427357D01*
X620188Y427625D01*
X619827Y427740D01*
X619465Y427663D01*
X619207Y427472D01*
X619103Y427242D01*
Y426858D01*
X618948Y426513D01*
X618638Y426283D01*
X618277Y426207D01*
X617915Y426283D01*
X617657Y426475D01*
X617502Y426782D01*
X617450Y427050D01*
G01X620550Y430150D02*
X620447Y429843D01*
X620188Y429613D01*
X619878Y429460D01*
X619465Y429345D01*
X619000Y429307D01*
X618535Y429345D01*
X618122Y429460D01*
X617812Y429613D01*
X617553Y429843D01*
X617450Y430150D01*
X617553Y430457D01*
X617812Y430687D01*
X618122Y430840D01*
X618535Y430955D01*
X619000Y430993D01*
X619465Y430955D01*
X619878Y430840D01*
X620188Y430687D01*
X620447Y430457D01*
X620550Y430150D01*
G01X643917Y89450D02*
Y92550D01*
X642958D01*
X642652Y92395D01*
X642460Y92188D01*
X642383Y91775D01*
X642460Y91362D01*
X642690Y91103D01*
X642958Y90948D01*
X643917D01*
G01X642958D02*
X642383Y89450D01*
G01X639590D02*
Y92550D01*
X641008Y90328D01*
X639092D01*
G01X636950Y89450D02*
Y92550D01*
X637410Y91930D01*
G01Y89450D02*
X636490D01*
G01X633850D02*
Y92550D01*
X634310Y91930D01*
G01Y89450D02*
X633390D01*
G01X643417Y110950D02*
Y114050D01*
X642458D01*
X642152Y113895D01*
X641960Y113688D01*
X641883Y113275D01*
X641960Y112862D01*
X642190Y112603D01*
X642458Y112448D01*
X643417D01*
G01X642458D02*
X641883Y110950D01*
G01X639090D02*
Y114050D01*
X640508Y111828D01*
X638592D01*
G01X636450Y110950D02*
Y114050D01*
X636910Y113430D01*
G01Y110950D02*
X635990D01*
G01X634193Y111415D02*
X633963Y111157D01*
X633695Y111002D01*
X633350Y110950D01*
X633005Y111053D01*
X632737Y111260D01*
X632545Y111622D01*
X632507Y112035D01*
X632583Y112448D01*
X632775Y112707D01*
X633043Y112913D01*
X633312Y112965D01*
X633580Y112913D01*
X633925Y112707D01*
X633810Y114050D01*
X632775D01*
G01X643417Y114950D02*
Y118050D01*
X642458D01*
X642152Y117895D01*
X641960Y117688D01*
X641883Y117275D01*
X641960Y116862D01*
X642190Y116603D01*
X642458Y116448D01*
X643417D01*
G01X642458D02*
X641883Y114950D01*
G01X639090D02*
Y118050D01*
X640508Y115828D01*
X638592D01*
G01X636450Y114950D02*
Y118050D01*
X636910Y117430D01*
G01Y114950D02*
X635990D01*
G01X633427D02*
X633350Y115622D01*
X633235Y116190D01*
X633082Y116707D01*
X632890Y117275D01*
X632583Y118050D01*
X634117D01*
G01X624950Y162457D02*
X628050D01*
Y163416D01*
X627895Y163722D01*
X627688Y163914D01*
X627275Y163991D01*
X626862Y163914D01*
X626603Y163684D01*
X626448Y163416D01*
Y162457D01*
G01Y163416D02*
X624950Y163991D01*
G01Y166324D02*
X628050D01*
X627430Y165864D01*
G01X624950D02*
Y166784D01*
G01X628050Y169424D02*
X627947Y169117D01*
X627688Y168887D01*
X627378Y168734D01*
X626965Y168619D01*
X626500Y168581D01*
X626035Y168619D01*
X625622Y168734D01*
X625312Y168887D01*
X625053Y169117D01*
X624950Y169424D01*
X625053Y169731D01*
X625312Y169961D01*
X625622Y170114D01*
X626035Y170229D01*
X626500Y170267D01*
X626965Y170229D01*
X627378Y170114D01*
X627688Y169961D01*
X627947Y169731D01*
X628050Y169424D01*
G01X625570Y171681D02*
X625208Y171911D01*
X625002Y172217D01*
X624950Y172562D01*
X625002Y172869D01*
X625260Y173176D01*
X625570Y173367D01*
X625880Y173406D01*
X626242Y173329D01*
X626500Y173061D01*
X626603Y172792D01*
Y172447D01*
G01Y172792D02*
X626758Y173022D01*
X627017Y173214D01*
X627327Y173291D01*
X627637Y173214D01*
X627895Y173022D01*
X628050Y172677D01*
X627998Y172332D01*
X627792Y171987D01*
G01X629450Y162457D02*
X632550D01*
Y163416D01*
X632395Y163722D01*
X632188Y163914D01*
X631775Y163991D01*
X631362Y163914D01*
X631103Y163684D01*
X630948Y163416D01*
Y162457D01*
G01Y163416D02*
X629450Y163991D01*
G01Y166324D02*
X632550D01*
X631930Y165864D01*
G01X629450D02*
Y166784D01*
G01X632550Y169424D02*
X632447Y169117D01*
X632188Y168887D01*
X631878Y168734D01*
X631465Y168619D01*
X631000Y168581D01*
X630535Y168619D01*
X630122Y168734D01*
X629812Y168887D01*
X629553Y169117D01*
X629450Y169424D01*
X629553Y169731D01*
X629812Y169961D01*
X630122Y170114D01*
X630535Y170229D01*
X631000Y170267D01*
X631465Y170229D01*
X631878Y170114D01*
X632188Y169961D01*
X632447Y169731D01*
X632550Y169424D01*
G01X632033Y171796D02*
X632343Y172026D01*
X632498Y172294D01*
X632550Y172601D01*
X632447Y172984D01*
X632188Y173252D01*
X631878Y173329D01*
X631568Y173291D01*
X631310Y173137D01*
X630793Y172371D01*
X630432Y172026D01*
X629915Y171796D01*
X629450Y171719D01*
Y173329D01*
G01X633950Y162457D02*
X637050D01*
Y163416D01*
X636895Y163722D01*
X636688Y163914D01*
X636275Y163991D01*
X635862Y163914D01*
X635603Y163684D01*
X635448Y163416D01*
Y162457D01*
G01Y163416D02*
X633950Y163991D01*
G01Y166324D02*
X637050D01*
X636430Y165864D01*
G01X633950D02*
Y166784D01*
G01X637050Y169424D02*
X636947Y169117D01*
X636688Y168887D01*
X636378Y168734D01*
X635965Y168619D01*
X635500Y168581D01*
X635035Y168619D01*
X634622Y168734D01*
X634312Y168887D01*
X634053Y169117D01*
X633950Y169424D01*
X634053Y169731D01*
X634312Y169961D01*
X634622Y170114D01*
X635035Y170229D01*
X635500Y170267D01*
X635965Y170229D01*
X636378Y170114D01*
X636688Y169961D01*
X636947Y169731D01*
X637050Y169424D01*
G01X633950Y172524D02*
X637050D01*
X636430Y172064D01*
G01X633950D02*
Y172984D01*
G54D13*
G01X227000Y236500D02*
X117000D01*
Y211500D01*
X227000D01*
Y236500D01*
G54D14*
G01X214965Y220753D02*
X214045Y219970D01*
X213010Y219500D01*
X212090D01*
X211170Y219970D01*
X210480Y220753D01*
X210135Y221850D01*
X210365Y222947D01*
X210940Y223887D01*
X211975Y224513D01*
X213355Y224827D01*
X214160Y225453D01*
X214505Y226550D01*
X214275Y227647D01*
X213700Y228430D01*
X212895Y228900D01*
X212090D01*
X211285Y228587D01*
X210595Y227803D01*
G01X201050Y219500D02*
X205650D01*
Y228900D01*
X201050D01*
G01X202890Y224357D02*
X205650D01*
G01X196450Y219500D02*
Y228900D01*
X193575D01*
X192655Y228430D01*
X192080Y227803D01*
X191850Y226550D01*
X192080Y225297D01*
X192770Y224513D01*
X193575Y224043D01*
X196450D01*
G01X193575D02*
X191850Y219500D01*
G01X186330Y228900D02*
X183570D01*
G01X184950D02*
Y219500D01*
G01X186330D02*
X183570D01*
G01X178625D02*
X175750Y228900D01*
X172875Y219500D01*
G01X173910Y222790D02*
X177590D01*
G01X168850Y228900D02*
Y219500D01*
X164250D01*
G01X150795D02*
Y228900D01*
X145505Y219500D01*
Y228900D01*
G01X138950Y219500D02*
X139870Y219657D01*
X140675Y220283D01*
X141365Y221223D01*
X141825Y222320D01*
X142055Y223573D01*
Y224827D01*
X141825Y226080D01*
X141365Y227177D01*
X140675Y228117D01*
X139870Y228743D01*
X138950Y228900D01*
X138030Y228743D01*
X137225Y228117D01*
X136535Y227177D01*
X136075Y226080D01*
X135845Y224827D01*
Y223573D01*
X136075Y222320D01*
X136535Y221223D01*
X137225Y220283D01*
X138030Y219657D01*
X138950Y219500D01*
G01X129750Y219187D02*
X129980Y219343D01*
Y219657D01*
X129750Y219813D01*
X129520Y219657D01*
Y219343D01*
X129750Y219187D01*
M02*
